FILE_TYPE = MACRO_DRAWING;
SET COLOR_WIRE YELLOW;
SET COLOR_PROP MONO;
SET COLOR_DOT WHITE;
SET COLOR_ARC YELLOW;
SET COLOR_BODY GREEN;
SET COLOR_NOTE MONO;
SET PROP_DISPLAY VALUE;
SET PAGE_NUMBER P156;
FORCEADD TTL2G07..1
(-3000 4150);
FORCEPROP 1 LAST PART_NUMBER D22707-001
J 0
(-3250 4000);
DISPLAY 0.617021 (-3250 4000);
PAINT BLUE (-3250 4000);
FORCEPROP 1 LAST POWER_GROUP VCC=P3V3_STBY;GND=GND
J 0
(-3250 3950);
DISPLAY 0.617021 (-3250 3950);
PAINT ORANGE (-3250 3950);
FORCEPROP 2 LASTPIN (-3300 4100) $PN 3
J 2
(-3310 4110);
DISPLAY 0.617021 (-3310 4110);
PAINT ORANGE (-3310 4110);
FORCEPROP 2 LASTPIN (-3300 4150) $PN 1
J 2
(-3310 4160);
DISPLAY 0.617021 (-3310 4160);
PAINT ORANGE (-3310 4160);
FORCEPROP 1 LAST MATERIAL IC
J 0
(-3250 4325);
DISPLAY 0.617021 (-3250 4325);
PAINT SKYBLUE (-3250 4325);
FORCEPROP 1 LAST LOCATION U8F3
J 0
(-3250 4375);
DISPLAY 0.617021 (-3250 4375);
PAINT AQUA (-3250 4375);
FORCEPROP 1 LAST VALUE 74LVC2G07
J 1
(-3000 4225);
DISPLAY 0.617021 (-3000 4225);
PAINT SKYBLUE (-3000 4225);
FORCEPROP 2 LASTPIN (-2700 4100) $PN 4
J 0
(-2690 4110);
DISPLAY 0.617021 (-2690 4110);
PAINT ORANGE (-2690 4110);
FORCEPROP 2 LASTPIN (-2700 4150) $PN 6
J 0
(-2690 4160);
DISPLAY 0.617021 (-2690 4160);
PAINT ORANGE (-2690 4160);
FORCEPROP 2 LAST BOM_COST SM_CONTROLLER
J 0
(-3250 4475);
DISPLAY 1.021277 (-3250 4475);
PAINT ORANGE (-3250 4475);
DISPLAY INVISIBLE (-3250 4475);
FORCEPROP 2 LAST SEC_TYPE SOT23LF
J 0
(-3250 4425);
DISPLAY 1.021277 (-3250 4425);
PAINT ORANGE (-3250 4425);
DISPLAY INVISIBLE (-3250 4425);
FORCEPROP 2 LAST SEC 1
J 0
(-3250 4425);
DISPLAY 0.680851 (-3250 4425);
PAINT MONO (-3250 4425);
DISPLAY INVISIBLE (-3250 4425);
FORCEPROP 2 LAST CDS_LOCATION U8F3
J 0
(-3250 4375);
DISPLAY 0.617021 (-3250 4375);
PAINT AQUA (-3250 4375);
DISPLAY INVISIBLE (-3250 4375);
FORCEPROP 2 LAST ROOM BMC_MISC
J 0
(-3250 4425);
DISPLAY 1.021277 (-3250 4425);
PAINT ORANGE (-3250 4425);
DISPLAY INVISIBLE (-3250 4425);
FORCEPROP 1 LAST PACK_TYPE SOT23LF
J 0
(-3250 4425);
PAINT SKYBLUE (-3250 4425);
DISPLAY INVISIBLE (-3250 4425);
FORCEPROP 2 LAST CDS_LIB mstr_ttl
J 0
(-3000 4150);
PAINT ORANGE (-3000 4150);
DISPLAY INVISIBLE (-3000 4150);
FORCEPROP 1 LAST PATH I201
J 0
(-2750 4325);
PAINT GREEN (-2750 4325);
DISPLAY INVISIBLE (-2750 4325);
FORCEADD OFFPAGE..1
(-4625 4150);
FORCEPROP 2 LAST $XR0 145 
J 0
(-4877 4150);
DISPLAY 0.638298 (-4877 4150);
PAINT MONO (-4877 4150);
FORCEPROP 2 LAST CDS_LIB mstr_standard
J 0
(-4625 4150);
PAINT ORANGE (-4625 4150);
DISPLAY INVISIBLE (-4625 4150);
FORCEPROP 2 LAST PATH I202
J 0
(-4575 4225);
DISPLAY 1.021277 (-4575 4225);
PAINT ORANGE (-4575 4225);
DISPLAY INVISIBLE (-4575 4225);
FORCEPROP 1 LAST OFFPAGE TRUE
J 0
(-4300 4025);
DISPLAY 0.872340 (-4300 4025);
PAINT GREEN (-4300 4025);
DISPLAY INVISIBLE (-4300 4025);
FORCEPROP 1 LAST COMMENT_BODY TRUE
J 0
(-4500 4050);
DISPLAY 0.872340 (-4500 4050);
PAINT GREEN (-4500 4050);
DISPLAY INVISIBLE (-4500 4050);
FORCEADD OFFPAGE..1
(-4625 4100);
FORCEPROP 2 LAST $XR0 145 
J 0
(-4877 4100);
DISPLAY 0.638298 (-4877 4100);
PAINT MONO (-4877 4100);
FORCEPROP 2 LAST CDS_LIB mstr_standard
J 0
(-4625 4100);
PAINT ORANGE (-4625 4100);
DISPLAY INVISIBLE (-4625 4100);
FORCEPROP 2 LAST PATH I203
J 0
(-4575 4175);
DISPLAY 1.021277 (-4575 4175);
PAINT ORANGE (-4575 4175);
DISPLAY INVISIBLE (-4575 4175);
FORCEPROP 1 LAST OFFPAGE TRUE
J 0
(-4300 3975);
DISPLAY 0.872340 (-4300 3975);
PAINT GREEN (-4300 3975);
DISPLAY INVISIBLE (-4300 3975);
FORCEPROP 1 LAST COMMENT_BODY TRUE
J 0
(-4500 4000);
DISPLAY 0.872340 (-4500 4000);
PAINT GREEN (-4500 4000);
DISPLAY INVISIBLE (-4500 4000);
FORCEADD OFFPAGE..2
(-950 4150);
FORCEPROP 2 LAST $XR0 191 
J 0
(-761 4150);
DISPLAY 0.638298 (-761 4150);
PAINT MONO (-761 4150);
FORCEPROP 2 LAST $XR1 118 
J 0
(-641 4150);
DISPLAY 0.638298 (-641 4150);
PAINT MONO (-641 4150);
FORCEPROP 2 LASTPIN (-1000 4150) SIG_NAME RST_BMC_SYSRST_BTN_OUT_B_N
J 2
(-1010 4160);
DISPLAY 0.617021 (-1010 4160);
PAINT ORANGE (-1010 4160);
FORCEPROP 2 LAST PATH I204
J 0
(-900 4225);
DISPLAY 1.021277 (-900 4225);
PAINT ORANGE (-900 4225);
DISPLAY INVISIBLE (-900 4225);
FORCEPROP 2 LAST CDS_LIB mstr_standard
J 0
(-950 4150);
PAINT ORANGE (-950 4150);
DISPLAY INVISIBLE (-950 4150);
FORCEPROP 1 LAST OFFPAGE TRUE
J 0
(-625 4025);
DISPLAY 0.872340 (-625 4025);
PAINT GREEN (-625 4025);
DISPLAY INVISIBLE (-625 4025);
FORCEPROP 1 LAST COMMENT_BODY TRUE
J 0
(-995 4055);
DISPLAY 0.872340 (-995 4055);
PAINT GREEN (-995 4055);
DISPLAY INVISIBLE (-995 4055);
FORCEADD OFFPAGE..2
(-950 4100);
FORCEPROP 2 LAST $XR0 191 
J 0
(-761 4100);
DISPLAY 0.638298 (-761 4100);
PAINT MONO (-761 4100);
FORCEPROP 2 LAST $XR1 118 
J 0
(-641 4100);
DISPLAY 0.638298 (-641 4100);
PAINT MONO (-641 4100);
FORCEPROP 2 LASTPIN (-1000 4100) SIG_NAME FM_PCH_PWRBTN_N
J 2
(-1010 4110);
DISPLAY 0.617021 (-1010 4110);
PAINT ORANGE (-1010 4110);
FORCEPROP 2 LAST CDS_LIB mstr_standard
J 0
(-950 4100);
PAINT ORANGE (-950 4100);
DISPLAY INVISIBLE (-950 4100);
FORCEPROP 2 LAST PATH I205
J 0
(-775 4175);
DISPLAY 1.021277 (-775 4175);
PAINT ORANGE (-775 4175);
DISPLAY INVISIBLE (-775 4175);
FORCEPROP 1 LAST OFFPAGE TRUE
J 0
(-625 3975);
DISPLAY 0.872340 (-625 3975);
PAINT GREEN (-625 3975);
DISPLAY INVISIBLE (-625 3975);
FORCEPROP 1 LAST COMMENT_BODY TRUE
J 0
(-995 4005);
DISPLAY 0.872340 (-995 4005);
PAINT GREEN (-995 4005);
DISPLAY INVISIBLE (-995 4005);
FORCEADD RES..2
(-4150 4450);
FORCEPROP 1 LASTPIN (-4150 4550) $PN 1
J 0
(-4145 4512);
DISPLAY 0.617021 (-4145 4512);
PAINT ORANGE (-4145 4512);
FORCEPROP 1 LASTPIN (-4150 4350) $PN 2
J 0
(-4145 4360);
DISPLAY 0.617021 (-4145 4360);
PAINT ORANGE (-4145 4360);
FORCEPROP 1 LAST WATTAGE 1/16W
J 0
(-4110 4425);
DISPLAY 0.617021 (-4110 4425);
PAINT SKYBLUE (-4110 4425);
FORCEPROP 1 LAST MATERIAL CHIP
J 0
(-4110 4375);
DISPLAY 0.617021 (-4110 4375);
PAINT SKYBLUE (-4110 4375);
FORCEPROP 1 LAST PACK_TYPE 0402
J 0
(-4110 4275);
DISPLAY 0.617021 (-4110 4275);
PAINT SKYBLUE (-4110 4275);
FORCEPROP 1 LAST TOLERANCE 1%
J 0
(-4105 4475);
DISPLAY 0.617021 (-4105 4475);
PAINT SKYBLUE (-4105 4475);
FORCEPROP 1 LAST VALUE 4.75K
J 0
(-4105 4525);
DISPLAY 0.617021 (-4105 4525);
PAINT SKYBLUE (-4105 4525);
FORCEPROP 1 LAST PART_NUMBER G21796-072
J 0
(-4110 4325);
DISPLAY 0.617021 (-4110 4325);
PAINT BLUE (-4110 4325);
FORCEPROP 1 LAST LOCATION R2T34
J 0
(-4105 4575);
DISPLAY 0.617021 (-4105 4575);
PAINT AQUA (-4105 4575);
FORCEPROP 2 LAST CDS_LOCATION R2T34
J 0
(-4105 4575);
DISPLAY 0.617021 (-4105 4575);
PAINT AQUA (-4105 4575);
DISPLAY INVISIBLE (-4105 4575);
FORCEPROP 2 LAST CDS_LIB mstr_discrete
J 0
(-4150 4450);
PAINT MONO (-4150 4450);
DISPLAY INVISIBLE (-4150 4450);
FORCEPROP 2 LAST BOM_COST SM_CONTROLLER
J 0
(-4100 4675);
DISPLAY 1.021277 (-4100 4675);
PAINT ORANGE (-4100 4675);
DISPLAY INVISIBLE (-4100 4675);
FORCEPROP 2 LAST SEC_TYPE 0402
J 0
(-4100 4675);
DISPLAY 1.021277 (-4100 4675);
PAINT ORANGE (-4100 4675);
DISPLAY INVISIBLE (-4100 4675);
FORCEPROP 2 LAST SEC 1
J 0
(-4100 4675);
PAINT MONO (-4100 4675);
DISPLAY INVISIBLE (-4100 4675);
FORCEPROP 1 LAST PATH I206
J 0
(-4100 4625);
DISPLAY 0.978723 (-4100 4625);
PAINT WHITE (-4100 4625);
DISPLAY INVISIBLE (-4100 4625);
FORCEPROP 2 LAST ROOM BMC_MISC
J 0
(-4100 4625);
DISPLAY 1.021277 (-4100 4625);
PAINT ORANGE (-4100 4625);
DISPLAY INVISIBLE (-4100 4625);
FORCEADD RES..2
(-3825 4450);
FORCEPROP 1 LAST PACK_TYPE 0402
J 0
(-3785 4275);
DISPLAY 0.617021 (-3785 4275);
PAINT SKYBLUE (-3785 4275);
FORCEPROP 1 LASTPIN (-3825 4350) $PN 2
J 0
(-3820 4360);
DISPLAY 0.617021 (-3820 4360);
PAINT ORANGE (-3820 4360);
FORCEPROP 1 LAST TOLERANCE 1%
J 0
(-3780 4475);
DISPLAY 0.617021 (-3780 4475);
PAINT SKYBLUE (-3780 4475);
FORCEPROP 1 LASTPIN (-3825 4550) $PN 1
J 0
(-3820 4512);
DISPLAY 0.617021 (-3820 4512);
PAINT ORANGE (-3820 4512);
FORCEPROP 1 LAST VALUE 4.75K
J 0
(-3780 4525);
DISPLAY 0.617021 (-3780 4525);
PAINT SKYBLUE (-3780 4525);
FORCEPROP 1 LAST LOCATION R2T35
J 0
(-3780 4575);
DISPLAY 0.617021 (-3780 4575);
PAINT AQUA (-3780 4575);
FORCEPROP 1 LAST MATERIAL CHIP
J 0
(-3785 4375);
DISPLAY 0.617021 (-3785 4375);
PAINT SKYBLUE (-3785 4375);
FORCEPROP 1 LAST WATTAGE 1/16W
J 0
(-3785 4425);
DISPLAY 0.617021 (-3785 4425);
PAINT SKYBLUE (-3785 4425);
FORCEPROP 1 LAST PART_NUMBER G21796-072
J 0
(-3785 4325);
DISPLAY 0.617021 (-3785 4325);
PAINT BLUE (-3785 4325);
FORCEPROP 2 LAST CDS_LOCATION R2T35
J 0
(-3780 4575);
DISPLAY 0.617021 (-3780 4575);
PAINT AQUA (-3780 4575);
DISPLAY INVISIBLE (-3780 4575);
FORCEPROP 2 LAST CDS_LIB mstr_discrete
J 0
(-3825 4450);
PAINT MONO (-3825 4450);
DISPLAY INVISIBLE (-3825 4450);
FORCEPROP 1 LAST PATH I207
J 0
(-3775 4625);
DISPLAY 0.978723 (-3775 4625);
PAINT WHITE (-3775 4625);
DISPLAY INVISIBLE (-3775 4625);
FORCEPROP 2 LAST SEC_TYPE 0402
J 0
(-3775 4675);
DISPLAY 1.021277 (-3775 4675);
PAINT ORANGE (-3775 4675);
DISPLAY INVISIBLE (-3775 4675);
FORCEPROP 2 LAST BOM_COST SM_CONTROLLER
J 0
(-3775 4675);
DISPLAY 1.021277 (-3775 4675);
PAINT ORANGE (-3775 4675);
DISPLAY INVISIBLE (-3775 4675);
FORCEPROP 2 LAST SEC 1
J 0
(-3775 4675);
PAINT MONO (-3775 4675);
DISPLAY INVISIBLE (-3775 4675);
FORCEPROP 2 LAST ROOM BMC_MISC
J 0
(-3775 4625);
DISPLAY 1.021277 (-3775 4625);
PAINT ORANGE (-3775 4625);
DISPLAY INVISIBLE (-3775 4625);
FORCEADD P3V3_STBY..1
(-4150 4850);
FORCEPROP 3 LASTPIN (-4150 4800) SIG_NAME P3V3_STBY\g
J 0
(-4140 4810);
DISPLAY 0.659574 (-4140 4810);
PAINT MONO (-4140 4810);
DISPLAY INVISIBLE (-4140 4810);
FORCEPROP 1 LAST VOLTAGE 3.3V
J 0
(-4195 4807);
DISPLAY 0.340426 (-4195 4807);
PAINT SKYBLUE (-4195 4807);
DISPLAY INVISIBLE (-4195 4807);
FORCEPROP 2 LAST CDS_LIB mstr_symbols
J 0
(-4150 4850);
PAINT ORANGE (-4150 4850);
DISPLAY INVISIBLE (-4150 4850);
FORCEPROP 1 LAST PATH I208
J 0
(-4105 4852);
DISPLAY 0.340426 (-4105 4852);
PAINT GREEN (-4105 4852);
DISPLAY INVISIBLE (-4105 4852);
FORCEPROP 1 LAST SIZE 1B
J 0
(-4105 4872);
DISPLAY 0.340426 (-4105 4872);
PAINT GREEN (-4105 4872);
DISPLAY INVISIBLE (-4105 4872);
FORCEPROP 1 LAST BODY_TYPE PLUMBING
J 0
(-4195 4807);
DISPLAY 0.340426 (-4195 4807);
PAINT GREEN (-4195 4807);
DISPLAY INVISIBLE (-4195 4807);
FORCEPROP 1 LAST HDL_POWER P3V3_STBY
J 0
(-4450 4725);
DISPLAY 0.872340 (-4450 4725);
PAINT ORANGE (-4450 4725);
DISPLAY INVISIBLE (-4450 4725);
FORCEADD P3V3_STBY..1
(-2400 4850);
FORCEPROP 3 LASTPIN (-2400 4800) SIG_NAME P3V3_STBY\g
J 0
(-2390 4810);
DISPLAY 0.659574 (-2390 4810);
PAINT MONO (-2390 4810);
DISPLAY INVISIBLE (-2390 4810);
FORCEPROP 1 LAST VOLTAGE 3.3V
J 0
(-2445 4807);
DISPLAY 0.340426 (-2445 4807);
PAINT SKYBLUE (-2445 4807);
DISPLAY INVISIBLE (-2445 4807);
FORCEPROP 1 LAST PATH I209
J 0
(-2355 4852);
DISPLAY 0.340426 (-2355 4852);
PAINT GREEN (-2355 4852);
DISPLAY INVISIBLE (-2355 4852);
FORCEPROP 2 LAST CDS_LIB mstr_symbols
J 0
(-2400 4850);
PAINT ORANGE (-2400 4850);
DISPLAY INVISIBLE (-2400 4850);
FORCEPROP 1 LAST SIZE 1B
J 0
(-2355 4872);
DISPLAY 0.340426 (-2355 4872);
PAINT GREEN (-2355 4872);
DISPLAY INVISIBLE (-2355 4872);
FORCEPROP 1 LAST BODY_TYPE PLUMBING
J 0
(-2445 4807);
DISPLAY 0.340426 (-2445 4807);
PAINT GREEN (-2445 4807);
DISPLAY INVISIBLE (-2445 4807);
FORCEPROP 1 LAST HDL_POWER P3V3_STBY
J 0
(-2700 4725);
DISPLAY 0.872340 (-2700 4725);
PAINT ORANGE (-2700 4725);
DISPLAY INVISIBLE (-2700 4725);
FORCEADD RES..2
(-2275 4425);
FORCEPROP 1 LAST PACK_TYPE 0402
J 0
(-2235 4250);
DISPLAY 0.617021 (-2235 4250);
PAINT SKYBLUE (-2235 4250);
FORCEPROP 1 LAST MATERIAL CHIP
J 0
(-2235 4350);
DISPLAY 0.617021 (-2235 4350);
PAINT SKYBLUE (-2235 4350);
FORCEPROP 1 LASTPIN (-2275 4325) $PN 2
J 0
(-2270 4335);
DISPLAY 0.617021 (-2270 4335);
PAINT ORANGE (-2270 4335);
FORCEPROP 1 LASTPIN (-2275 4525) $PN 1
J 0
(-2270 4487);
DISPLAY 0.617021 (-2270 4487);
PAINT ORANGE (-2270 4487);
FORCEPROP 1 LAST VALUE 10.0K
J 0
(-2230 4500);
DISPLAY 0.617021 (-2230 4500);
PAINT SKYBLUE (-2230 4500);
FORCEPROP 1 LAST TOLERANCE 1%
J 0
(-2230 4450);
DISPLAY 0.617021 (-2230 4450);
PAINT SKYBLUE (-2230 4450);
FORCEPROP 1 LAST LOCATION R2T22
J 0
(-2230 4550);
DISPLAY 0.617021 (-2230 4550);
PAINT AQUA (-2230 4550);
FORCEPROP 1 LAST WATTAGE 1/16W
J 0
(-2235 4400);
DISPLAY 0.617021 (-2235 4400);
PAINT SKYBLUE (-2235 4400);
FORCEPROP 1 LAST PART_NUMBER G21796-016
J 0
(-2235 4300);
DISPLAY 0.617021 (-2235 4300);
PAINT BLUE (-2235 4300);
FORCEPROP 2 LAST CDS_LIB mstr_discrete
J 0
(-2275 4425);
PAINT ORANGE (-2275 4425);
DISPLAY INVISIBLE (-2275 4425);
FORCEPROP 2 LAST CDS_LOCATION R2T22
J 0
(-2230 4550);
DISPLAY 0.617021 (-2230 4550);
PAINT AQUA (-2230 4550);
DISPLAY INVISIBLE (-2230 4550);
FORCEPROP 1 LAST PATH I210
J 0
(-2225 4600);
DISPLAY 0.978723 (-2225 4600);
PAINT WHITE (-2225 4600);
DISPLAY INVISIBLE (-2225 4600);
FORCEPROP 2 LAST ROOM BMC_MISC
J 0
(-2225 4600);
DISPLAY 1.021277 (-2225 4600);
PAINT ORANGE (-2225 4600);
DISPLAY INVISIBLE (-2225 4600);
FORCEPROP 2 LAST SEC 1
J 0
(-2225 4650);
DISPLAY 0.680851 (-2225 4650);
PAINT MONO (-2225 4650);
DISPLAY INVISIBLE (-2225 4650);
FORCEPROP 2 LAST SEC_TYPE 0402
J 0
(-2225 4650);
DISPLAY 1.021277 (-2225 4650);
PAINT ORANGE (-2225 4650);
DISPLAY INVISIBLE (-2225 4650);
FORCEPROP 2 LAST BOM_COST SM_CONTROLLER
J 0
(-2225 4650);
DISPLAY 1.021277 (-2225 4650);
PAINT ORANGE (-2225 4650);
DISPLAY INVISIBLE (-2225 4650);
FORCEADD RES..2
(-2550 4450);
FORCEPROP 1 LAST PACK_TYPE 0402
J 0
(-2510 4275);
DISPLAY 0.617021 (-2510 4275);
PAINT SKYBLUE (-2510 4275);
FORCEPROP 1 LAST LOCATION R8F26
J 0
(-2505 4575);
DISPLAY 0.617021 (-2505 4575);
PAINT AQUA (-2505 4575);
FORCEPROP 1 LAST VALUE 10.0K
J 0
(-2505 4525);
DISPLAY 0.617021 (-2505 4525);
PAINT SKYBLUE (-2505 4525);
FORCEPROP 1 LAST TOLERANCE 1%
J 0
(-2505 4475);
DISPLAY 0.617021 (-2505 4475);
PAINT SKYBLUE (-2505 4475);
FORCEPROP 1 LAST MATERIAL CHIP
J 0
(-2510 4375);
DISPLAY 0.617021 (-2510 4375);
PAINT SKYBLUE (-2510 4375);
FORCEPROP 1 LAST WATTAGE 1/16W
J 0
(-2510 4425);
DISPLAY 0.617021 (-2510 4425);
PAINT SKYBLUE (-2510 4425);
FORCEPROP 1 LASTPIN (-2550 4550) $PN 1
J 0
(-2545 4512);
DISPLAY 0.617021 (-2545 4512);
PAINT ORANGE (-2545 4512);
FORCEPROP 1 LASTPIN (-2550 4350) $PN 2
J 0
(-2545 4360);
DISPLAY 0.617021 (-2545 4360);
PAINT ORANGE (-2545 4360);
FORCEPROP 1 LAST PART_NUMBER G21796-016
J 0
(-2510 4325);
DISPLAY 0.617021 (-2510 4325);
PAINT BLUE (-2510 4325);
FORCEPROP 2 LAST CDS_LOCATION R8F26
J 0
(-2505 4575);
DISPLAY 0.617021 (-2505 4575);
PAINT AQUA (-2505 4575);
DISPLAY INVISIBLE (-2505 4575);
FORCEPROP 2 LAST CDS_LIB mstr_discrete
J 0
(-2550 4450);
PAINT ORANGE (-2550 4450);
DISPLAY INVISIBLE (-2550 4450);
FORCEPROP 2 LAST ROOM BMC_MISC
J 0
(-2500 4625);
DISPLAY 1.021277 (-2500 4625);
PAINT ORANGE (-2500 4625);
DISPLAY INVISIBLE (-2500 4625);
FORCEPROP 1 LAST PATH I211
J 0
(-2500 4625);
DISPLAY 0.978723 (-2500 4625);
PAINT WHITE (-2500 4625);
DISPLAY INVISIBLE (-2500 4625);
FORCEPROP 2 LAST SEC 1
J 0
(-2500 4675);
DISPLAY 0.680851 (-2500 4675);
PAINT MONO (-2500 4675);
DISPLAY INVISIBLE (-2500 4675);
FORCEPROP 2 LAST SEC_TYPE 0402
J 0
(-2500 4675);
DISPLAY 1.021277 (-2500 4675);
PAINT ORANGE (-2500 4675);
DISPLAY INVISIBLE (-2500 4675);
FORCEPROP 2 LAST BOM_COST SM_CONTROLLER
J 0
(-2500 4675);
DISPLAY 1.021277 (-2500 4675);
PAINT ORANGE (-2500 4675);
DISPLAY INVISIBLE (-2500 4675);
FORCEADD OFFPAGE..1
(-7450 2775);
FORCEPROP 2 LAST $XR0 120 
J 0
(-7732 2775);
DISPLAY 0.638298 (-7732 2775);
PAINT MONO (-7732 2775);
FORCEPROP 2 LAST $XR1 145 
J 0
(-7852 2775);
DISPLAY 0.638298 (-7852 2775);
PAINT MONO (-7852 2775);
FORCEPROP 2 LAST $XR2 ?
J 0
(-7852 2775);
DISPLAY 0.638298 (-7852 2775);
PAINT MONO (-7852 2775);
FORCEPROP 2 LAST CDS_LIB mstr_standard
J 0
(-7450 2775);
PAINT ORANGE (-7450 2775);
DISPLAY INVISIBLE (-7450 2775);
FORCEPROP 2 LAST PATH I212
J 0
(-7400 2850);
DISPLAY 1.021277 (-7400 2850);
PAINT ORANGE (-7400 2850);
DISPLAY INVISIBLE (-7400 2850);
FORCEPROP 1 LAST OFFPAGE TRUE
J 0
(-7125 2650);
DISPLAY 0.872340 (-7125 2650);
PAINT GREEN (-7125 2650);
DISPLAY INVISIBLE (-7125 2650);
FORCEPROP 1 LAST COMMENT_BODY TRUE
J 0
(-7325 2675);
DISPLAY 0.872340 (-7325 2675);
PAINT GREEN (-7325 2675);
DISPLAY INVISIBLE (-7325 2675);
FORCEADD OFFPAGE..2
(-5850 2775);
FORCEPROP 2 LAST $XR0 119 
J 0
(-5661 2775);
DISPLAY 0.638298 (-5661 2775);
PAINT MONO (-5661 2775);
FORCEPROP 2 LAST CDS_LIB mstr_standard
J 0
(-5850 2775);
PAINT ORANGE (-5850 2775);
DISPLAY INVISIBLE (-5850 2775);
FORCEPROP 2 LAST PATH I213
J 0
(-5800 2850);
DISPLAY 1.021277 (-5800 2850);
PAINT ORANGE (-5800 2850);
DISPLAY INVISIBLE (-5800 2850);
FORCEPROP 1 LAST OFFPAGE TRUE
J 0
(-5525 2650);
DISPLAY 0.872340 (-5525 2650);
PAINT GREEN (-5525 2650);
DISPLAY INVISIBLE (-5525 2650);
FORCEPROP 1 LAST COMMENT_BODY TRUE
J 0
(-5895 2680);
DISPLAY 0.872340 (-5895 2680);
PAINT GREEN (-5895 2680);
DISPLAY INVISIBLE (-5895 2680);
FORCEADD RES..1
(-6575 2775);
FORCEPROP 1 LASTPIN (-6675 2775) $PN 1
J 0
(-6663 2787);
DISPLAY 0.617021 (-6663 2787);
PAINT ORANGE (-6663 2787);
FORCEPROP 1 LAST WATTAGE 1/16W
J 2
(-6600 2625);
DISPLAY 0.617021 (-6600 2625);
PAINT SKYBLUE (-6600 2625);
FORCEPROP 1 LAST VALUE 33.2
J 2
(-6600 2675);
DISPLAY 0.617021 (-6600 2675);
PAINT SKYBLUE (-6600 2675);
FORCEPROP 1 LAST PART_NUMBER G21796-074
J 0
(-6700 2575);
DISPLAY 0.617021 (-6700 2575);
PAINT BLUE (-6700 2575);
FORCEPROP 1 LASTPIN (-6475 2775) $PN 2
J 0
(-6513 2787);
DISPLAY 0.617021 (-6513 2787);
PAINT ORANGE (-6513 2787);
FORCEPROP 1 LAST MATERIAL CHIP
J 0
(-6575 2625);
DISPLAY 0.617021 (-6575 2625);
PAINT SKYBLUE (-6575 2625);
FORCEPROP 1 LAST TOLERANCE 1%
J 0
(-6575 2675);
DISPLAY 0.617021 (-6575 2675);
PAINT SKYBLUE (-6575 2675);
FORCEPROP 1 LAST LOCATION R8E24
J 0
(-6625 2825);
DISPLAY 0.617021 (-6625 2825);
PAINT AQUA (-6625 2825);
FORCEPROP 1 LAST PACK_TYPE 0402
J 0
(-6325 2625);
DISPLAY 0.617021 (-6325 2625);
PAINT SKYBLUE (-6325 2625);
FORCEPROP 2 LAST CDS_LIB mstr_discrete
J 0
(-6575 2775);
PAINT MONO (-6575 2775);
DISPLAY INVISIBLE (-6575 2775);
FORCEPROP 2 LAST SEC_TYPE 0402
J 0
(-6625 2975);
DISPLAY 1.021277 (-6625 2975);
PAINT ORANGE (-6625 2975);
DISPLAY INVISIBLE (-6625 2975);
FORCEPROP 2 LAST BOM_COST SM_CONTROLLER
J 0
(-6625 2975);
DISPLAY 1.021277 (-6625 2975);
PAINT ORANGE (-6625 2975);
DISPLAY INVISIBLE (-6625 2975);
FORCEPROP 2 LAST SEC 1
J 0
(-6625 2975);
DISPLAY 0.680851 (-6625 2975);
PAINT MONO (-6625 2975);
DISPLAY INVISIBLE (-6625 2975);
FORCEPROP 2 LAST CDS_LOCATION R8E24
J 0
(-6625 2825);
DISPLAY 0.617021 (-6625 2825);
PAINT AQUA (-6625 2825);
DISPLAY INVISIBLE (-6625 2825);
FORCEPROP 2 LAST ROOM BMC_MISC
J 0
(-6625 2925);
DISPLAY 1.021277 (-6625 2925);
PAINT ORANGE (-6625 2925);
DISPLAY INVISIBLE (-6625 2925);
FORCEPROP 1 LAST PATH I214
J 0
(-6625 2925);
DISPLAY 0.978723 (-6625 2925);
PAINT WHITE (-6625 2925);
DISPLAY INVISIBLE (-6625 2925);
FORCEADD RES..2
(-6825 3025);
FORCEPROP 1 LASTPIN (-6825 2925) $PN 2
J 0
(-6820 2935);
DISPLAY 0.617021 (-6820 2935);
PAINT ORANGE (-6820 2935);
FORCEPROP 1 LAST MATERIAL CHIP
J 0
(-6785 2950);
DISPLAY 0.617021 (-6785 2950);
PAINT SKYBLUE (-6785 2950);
FORCEPROP 1 LAST PACK_TYPE 0402
J 0
(-6785 2850);
DISPLAY 0.617021 (-6785 2850);
PAINT SKYBLUE (-6785 2850);
FORCEPROP 1 LAST WATTAGE 1/16W
J 0
(-6785 3000);
DISPLAY 0.617021 (-6785 3000);
PAINT SKYBLUE (-6785 3000);
FORCEPROP 1 LAST PART_NUMBER G21796-072
J 0
(-6785 2900);
DISPLAY 0.617021 (-6785 2900);
PAINT BLUE (-6785 2900);
FORCEPROP 1 LAST TOLERANCE 1%
J 0
(-6780 3050);
DISPLAY 0.617021 (-6780 3050);
PAINT SKYBLUE (-6780 3050);
FORCEPROP 1 LASTPIN (-6825 3125) $PN 1
J 0
(-6820 3087);
DISPLAY 0.617021 (-6820 3087);
PAINT ORANGE (-6820 3087);
FORCEPROP 1 LAST VALUE 4.75K
J 0
(-6780 3100);
DISPLAY 0.617021 (-6780 3100);
PAINT SKYBLUE (-6780 3100);
FORCEPROP 1 LAST LOCATION R8E22
J 0
(-6780 3150);
DISPLAY 0.617021 (-6780 3150);
PAINT AQUA (-6780 3150);
FORCEPROP 2 LAST CDS_LIB mstr_discrete
J 0
(-6825 3025);
PAINT ORANGE (-6825 3025);
DISPLAY INVISIBLE (-6825 3025);
FORCEPROP 2 LAST SEC_TYPE 0402
J 0
(-6775 3250);
DISPLAY 1.021277 (-6775 3250);
PAINT ORANGE (-6775 3250);
DISPLAY INVISIBLE (-6775 3250);
FORCEPROP 2 LAST BOM_COST SM_CONTROLLER
J 0
(-6775 3250);
DISPLAY 1.021277 (-6775 3250);
PAINT ORANGE (-6775 3250);
DISPLAY INVISIBLE (-6775 3250);
FORCEPROP 0 LAST SEC 1
J 0
(-6775 3200);
DISPLAY 0.680851 (-6775 3200);
PAINT MONO (-6775 3200);
DISPLAY INVISIBLE (-6775 3200);
FORCEPROP 2 LAST CDS_LOCATION R8E22
J 0
(-6780 3150);
DISPLAY 0.617021 (-6780 3150);
PAINT AQUA (-6780 3150);
DISPLAY INVISIBLE (-6780 3150);
FORCEPROP 1 LAST PATH I215
J 0
(-6775 3200);
DISPLAY 0.978723 (-6775 3200);
PAINT WHITE (-6775 3200);
DISPLAY INVISIBLE (-6775 3200);
FORCEPROP 2 LAST ROOM BMC_MISC
J 0
(-6775 3200);
DISPLAY 1.021277 (-6775 3200);
PAINT ORANGE (-6775 3200);
DISPLAY INVISIBLE (-6775 3200);
FORCEADD P3V3_STBY..1
(-6825 3275);
FORCEPROP 3 LASTPIN (-6825 3225) SIG_NAME P3V3_STBY\g
J 0
(-6815 3235);
DISPLAY 0.659574 (-6815 3235);
PAINT MONO (-6815 3235);
DISPLAY INVISIBLE (-6815 3235);
FORCEPROP 2 LAST CDS_LIB mstr_symbols
J 0
(-6825 3275);
PAINT ORANGE (-6825 3275);
DISPLAY INVISIBLE (-6825 3275);
FORCEPROP 1 LAST VOLTAGE 3.3V
J 0
(-6870 3232);
DISPLAY 0.340426 (-6870 3232);
PAINT SKYBLUE (-6870 3232);
DISPLAY INVISIBLE (-6870 3232);
FORCEPROP 1 LAST SIZE 1B
J 0
(-6780 3297);
DISPLAY 0.340426 (-6780 3297);
PAINT GREEN (-6780 3297);
DISPLAY INVISIBLE (-6780 3297);
FORCEPROP 1 LAST PATH I216
J 0
(-6780 3277);
DISPLAY 0.340426 (-6780 3277);
PAINT GREEN (-6780 3277);
DISPLAY INVISIBLE (-6780 3277);
FORCEPROP 1 LAST BODY_TYPE PLUMBING
J 0
(-6870 3232);
DISPLAY 0.340426 (-6870 3232);
PAINT GREEN (-6870 3232);
DISPLAY INVISIBLE (-6870 3232);
FORCEPROP 1 LAST HDL_POWER P3V3_STBY
J 0
(-7125 3150);
DISPLAY 0.872340 (-7125 3150);
PAINT ORANGE (-7125 3150);
DISPLAY INVISIBLE (-7125 3150);
FORCEADD GND..1
(-7275 4225);
FORCEPROP 3 LASTPIN (-7275 4275) SIG_NAME GND\g
J 0
(-7265 4285);
DISPLAY 0.659574 (-7265 4285);
PAINT MONO (-7265 4285);
DISPLAY INVISIBLE (-7265 4285);
FORCEPROP 1 LAST VOLTAGE 0.0V
J 0
(-7320 4182);
DISPLAY 0.340426 (-7320 4182);
PAINT SKYBLUE (-7320 4182);
DISPLAY INVISIBLE (-7320 4182);
FORCEPROP 1 LAST PATH I257
J 0
(-7200 4225);
DISPLAY 0.872340 (-7200 4225);
PAINT AQUA (-7200 4225);
DISPLAY INVISIBLE (-7200 4225);
FORCEPROP 1 LAST SIZE 1B
J 0
(-7200 4175);
DISPLAY 0.872340 (-7200 4175);
PAINT AQUA (-7200 4175);
DISPLAY INVISIBLE (-7200 4175);
FORCEPROP 2 LAST CDS_LIB mstr_symbols
J 0
(-7275 4225);
PAINT MONO (-7275 4225);
DISPLAY INVISIBLE (-7275 4225);
FORCEPROP 1 LAST BODY_TYPE PLUMBING
J 0
(-7320 4182);
DISPLAY 0.340426 (-7320 4182);
PAINT GREEN (-7320 4182);
DISPLAY INVISIBLE (-7320 4182);
FORCEPROP 1 LAST HDL_POWER GND
J 0
(-7275 4375);
DISPLAY 0.872340 (-7275 4375);
PAINT GREEN (-7275 4375);
DISPLAY INVISIBLE (-7275 4375);
FORCEADD RES..2
(-3750 3550);
FORCEPROP 1 LAST PACK_TYPE 0402
J 0
(-3710 3375);
DISPLAY 0.617021 (-3710 3375);
PAINT SKYBLUE (-3710 3375);
FORCEPROP 1 LAST MATERIAL CHIP
J 0
(-3710 3475);
DISPLAY 0.617021 (-3710 3475);
PAINT SKYBLUE (-3710 3475);
FORCEPROP 1 LASTPIN (-3750 3450) $PN 2
J 0
(-3745 3460);
DISPLAY 0.617021 (-3745 3460);
PAINT ORANGE (-3745 3460);
FORCEPROP 1 LAST TOLERANCE 1%
J 0
(-3705 3575);
DISPLAY 0.617021 (-3705 3575);
PAINT SKYBLUE (-3705 3575);
FORCEPROP 1 LASTPIN (-3750 3650) $PN 1
J 0
(-3745 3612);
DISPLAY 0.617021 (-3745 3612);
PAINT ORANGE (-3745 3612);
FORCEPROP 1 LAST LOCATION R2U2
J 0
(-3705 3675);
DISPLAY 0.617021 (-3705 3675);
PAINT AQUA (-3705 3675);
FORCEPROP 1 LAST WATTAGE 1/16W
J 0
(-3710 3525);
DISPLAY 0.617021 (-3710 3525);
PAINT SKYBLUE (-3710 3525);
FORCEPROP 1 LAST VALUE 4.75K
J 0
(-3705 3625);
DISPLAY 0.617021 (-3705 3625);
PAINT SKYBLUE (-3705 3625);
FORCEPROP 1 LAST PART_NUMBER G21796-072
J 0
(-3710 3425);
DISPLAY 0.617021 (-3710 3425);
PAINT BLUE (-3710 3425);
FORCEPROP 2 LAST CDS_LIB mstr_discrete
J 0
(-3750 3550);
PAINT MONO (-3750 3550);
DISPLAY INVISIBLE (-3750 3550);
FORCEPROP 2 LAST BOM_COST SM_CONTROLLER
J 0
(-3700 3775);
DISPLAY 1.021277 (-3700 3775);
PAINT ORANGE (-3700 3775);
DISPLAY INVISIBLE (-3700 3775);
FORCEPROP 2 LAST SEC_TYPE 0402
J 0
(-3700 3775);
DISPLAY 1.021277 (-3700 3775);
PAINT ORANGE (-3700 3775);
DISPLAY INVISIBLE (-3700 3775);
FORCEPROP 2 LAST SEC 1
J 0
(-3700 3775);
PAINT MONO (-3700 3775);
DISPLAY INVISIBLE (-3700 3775);
FORCEPROP 2 LAST CDS_LOCATION R2U2
J 0
(-3705 3675);
DISPLAY 0.617021 (-3705 3675);
PAINT AQUA (-3705 3675);
DISPLAY INVISIBLE (-3705 3675);
FORCEPROP 1 LAST PATH I265
J 0
(-3700 3725);
DISPLAY 0.978723 (-3700 3725);
PAINT WHITE (-3700 3725);
DISPLAY INVISIBLE (-3700 3725);
FORCEPROP 2 LAST ROOM BMC_MISC
J 0
(-3700 3725);
DISPLAY 1.021277 (-3700 3725);
PAINT ORANGE (-3700 3725);
DISPLAY INVISIBLE (-3700 3725);
FORCEADD P3V3_STBY..1
(-4075 3950);
FORCEPROP 3 LASTPIN (-4075 3900) SIG_NAME P3V3_STBY\g
J 0
(-4065 3910);
DISPLAY 0.659574 (-4065 3910);
PAINT MONO (-4065 3910);
DISPLAY INVISIBLE (-4065 3910);
FORCEPROP 1 LAST VOLTAGE 3.3V
J 0
(-4120 3907);
DISPLAY 0.340426 (-4120 3907);
PAINT SKYBLUE (-4120 3907);
DISPLAY INVISIBLE (-4120 3907);
FORCEPROP 1 LAST SIZE 1B
J 0
(-4030 3972);
DISPLAY 0.340426 (-4030 3972);
PAINT GREEN (-4030 3972);
DISPLAY INVISIBLE (-4030 3972);
FORCEPROP 2 LAST CDS_LIB mstr_symbols
J 0
(-4075 3950);
PAINT ORANGE (-4075 3950);
DISPLAY INVISIBLE (-4075 3950);
FORCEPROP 1 LAST PATH I266
J 0
(-4030 3952);
DISPLAY 0.340426 (-4030 3952);
PAINT GREEN (-4030 3952);
DISPLAY INVISIBLE (-4030 3952);
FORCEPROP 1 LAST BODY_TYPE PLUMBING
J 0
(-4120 3907);
DISPLAY 0.340426 (-4120 3907);
PAINT GREEN (-4120 3907);
DISPLAY INVISIBLE (-4120 3907);
FORCEPROP 1 LAST HDL_POWER P3V3_STBY
J 0
(-4375 3825);
DISPLAY 0.872340 (-4375 3825);
PAINT ORANGE (-4375 3825);
DISPLAY INVISIBLE (-4375 3825);
FORCEADD RES..2
(-4075 3550);
FORCEPROP 1 LAST PACK_TYPE 0402
J 0
(-4035 3375);
DISPLAY 0.617021 (-4035 3375);
PAINT SKYBLUE (-4035 3375);
FORCEPROP 1 LAST MATERIAL CHIP
J 0
(-4035 3475);
DISPLAY 0.617021 (-4035 3475);
PAINT SKYBLUE (-4035 3475);
FORCEPROP 1 LAST WATTAGE 1/16W
J 0
(-4035 3525);
DISPLAY 0.617021 (-4035 3525);
PAINT SKYBLUE (-4035 3525);
FORCEPROP 1 LASTPIN (-4075 3450) $PN 2
J 0
(-4070 3460);
DISPLAY 0.617021 (-4070 3460);
PAINT ORANGE (-4070 3460);
FORCEPROP 1 LAST PART_NUMBER G21796-072
J 0
(-4035 3425);
DISPLAY 0.617021 (-4035 3425);
PAINT BLUE (-4035 3425);
FORCEPROP 1 LAST TOLERANCE 1%
J 0
(-4030 3575);
DISPLAY 0.617021 (-4030 3575);
PAINT SKYBLUE (-4030 3575);
FORCEPROP 1 LASTPIN (-4075 3650) $PN 1
J 0
(-4070 3612);
DISPLAY 0.617021 (-4070 3612);
PAINT ORANGE (-4070 3612);
FORCEPROP 1 LAST VALUE 4.75K
J 0
(-4030 3625);
DISPLAY 0.617021 (-4030 3625);
PAINT SKYBLUE (-4030 3625);
FORCEPROP 1 LAST LOCATION R8G2
J 0
(-4030 3675);
DISPLAY 0.617021 (-4030 3675);
PAINT AQUA (-4030 3675);
FORCEPROP 2 LAST CDS_LIB mstr_discrete
J 0
(-4075 3550);
PAINT MONO (-4075 3550);
DISPLAY INVISIBLE (-4075 3550);
FORCEPROP 2 LAST CDS_LOCATION R8G2
J 0
(-4030 3675);
DISPLAY 0.617021 (-4030 3675);
PAINT AQUA (-4030 3675);
DISPLAY INVISIBLE (-4030 3675);
FORCEPROP 2 LAST SEC_TYPE 0402
J 0
(-4025 3775);
DISPLAY 1.021277 (-4025 3775);
PAINT ORANGE (-4025 3775);
DISPLAY INVISIBLE (-4025 3775);
FORCEPROP 2 LAST BOM_COST SM_CONTROLLER
J 0
(-4025 3775);
DISPLAY 1.021277 (-4025 3775);
PAINT ORANGE (-4025 3775);
DISPLAY INVISIBLE (-4025 3775);
FORCEPROP 2 LAST SEC 1
J 0
(-4025 3775);
PAINT MONO (-4025 3775);
DISPLAY INVISIBLE (-4025 3775);
FORCEPROP 2 LAST ROOM BMC_MISC
J 0
(-4025 3725);
DISPLAY 1.021277 (-4025 3725);
PAINT ORANGE (-4025 3725);
DISPLAY INVISIBLE (-4025 3725);
FORCEPROP 1 LAST PATH I267
J 0
(-4025 3725);
DISPLAY 0.978723 (-4025 3725);
PAINT WHITE (-4025 3725);
DISPLAY INVISIBLE (-4025 3725);
FORCEADD TTL2G07..1
(-2925 3250);
FORCEPROP 1 LAST MATERIAL IC
J 0
(-3175 3425);
DISPLAY 0.617021 (-3175 3425);
PAINT SKYBLUE (-3175 3425);
FORCEPROP 2 LASTPIN (-3225 3250) $PN 1
J 2
(-3235 3260);
DISPLAY 0.617021 (-3235 3260);
PAINT ORANGE (-3235 3260);
FORCEPROP 2 LASTPIN (-3225 3200) $PN 3
J 2
(-3235 3210);
DISPLAY 0.617021 (-3235 3210);
PAINT ORANGE (-3235 3210);
FORCEPROP 1 LAST PART_NUMBER D22707-001
J 0
(-3175 3100);
DISPLAY 0.617021 (-3175 3100);
PAINT BLUE (-3175 3100);
FORCEPROP 1 LAST LOCATION U8G1
J 0
(-3175 3475);
DISPLAY 0.617021 (-3175 3475);
PAINT AQUA (-3175 3475);
FORCEPROP 1 LAST POWER_GROUP VCC=P3V3_STBY;GND=GND
J 0
(-3175 3050);
DISPLAY 0.617021 (-3175 3050);
PAINT ORANGE (-3175 3050);
FORCEPROP 2 LASTPIN (-2625 3200) $PN 4
J 0
(-2615 3210);
DISPLAY 0.617021 (-2615 3210);
PAINT ORANGE (-2615 3210);
FORCEPROP 2 LASTPIN (-2625 3250) $PN 6
J 0
(-2615 3260);
DISPLAY 0.617021 (-2615 3260);
PAINT ORANGE (-2615 3260);
FORCEPROP 1 LAST VALUE 74LVC2G07
J 1
(-2925 3325);
DISPLAY 0.617021 (-2925 3325);
PAINT SKYBLUE (-2925 3325);
FORCEPROP 1 LAST PACK_TYPE SOT23LF
J 0
(-3175 3525);
PAINT SKYBLUE (-3175 3525);
DISPLAY INVISIBLE (-3175 3525);
FORCEPROP 2 LAST ROOM BMC_MISC
J 0
(-3175 3525);
DISPLAY 1.021277 (-3175 3525);
PAINT ORANGE (-3175 3525);
DISPLAY INVISIBLE (-3175 3525);
FORCEPROP 2 LAST CDS_LOCATION U8G1
J 0
(-3175 3475);
DISPLAY 0.617021 (-3175 3475);
PAINT AQUA (-3175 3475);
DISPLAY INVISIBLE (-3175 3475);
FORCEPROP 2 LAST SEC 1
J 0
(-3175 3525);
DISPLAY 0.680851 (-3175 3525);
PAINT MONO (-3175 3525);
DISPLAY INVISIBLE (-3175 3525);
FORCEPROP 2 LAST SEC_TYPE SOT23LF
J 0
(-3175 3525);
DISPLAY 1.021277 (-3175 3525);
PAINT ORANGE (-3175 3525);
DISPLAY INVISIBLE (-3175 3525);
FORCEPROP 2 LAST BOM_COST SM_CONTROLLER
J 0
(-3175 3575);
DISPLAY 1.021277 (-3175 3575);
PAINT ORANGE (-3175 3575);
DISPLAY INVISIBLE (-3175 3575);
FORCEPROP 2 LAST CDS_LIB mstr_ttl
J 0
(-2925 3250);
PAINT ORANGE (-2925 3250);
DISPLAY INVISIBLE (-2925 3250);
FORCEPROP 1 LAST PATH I269
J 0
(-2675 3425);
PAINT GREEN (-2675 3425);
DISPLAY INVISIBLE (-2675 3425);
FORCEADD OFFPAGE..1
(-4550 3250);
FORCEPROP 2 LAST $XR0 119 
J 0
(-4802 3250);
DISPLAY 0.638298 (-4802 3250);
PAINT MONO (-4802 3250);
FORCEPROP 2 LAST PATH I270
J 0
(-4800 3300);
DISPLAY 1.021277 (-4800 3300);
PAINT ORANGE (-4800 3300);
DISPLAY INVISIBLE (-4800 3300);
FORCEPROP 2 LAST CDS_LIB mstr_standard
J 0
(-4550 3250);
PAINT ORANGE (-4550 3250);
DISPLAY INVISIBLE (-4550 3250);
FORCEPROP 1 LAST OFFPAGE TRUE
J 0
(-4225 3125);
DISPLAY 0.872340 (-4225 3125);
PAINT GREEN (-4225 3125);
DISPLAY INVISIBLE (-4225 3125);
FORCEPROP 1 LAST COMMENT_BODY TRUE
J 0
(-4425 3150);
DISPLAY 0.872340 (-4425 3150);
PAINT GREEN (-4425 3150);
DISPLAY INVISIBLE (-4425 3150);
FORCEADD OFFPAGE..1
(-4550 3200);
FORCEPROP 2 LAST $XR0 119 
J 0
(-4802 3200);
DISPLAY 0.638298 (-4802 3200);
PAINT MONO (-4802 3200);
FORCEPROP 2 LAST PATH I271
J 0
(-4800 3250);
DISPLAY 1.021277 (-4800 3250);
PAINT ORANGE (-4800 3250);
DISPLAY INVISIBLE (-4800 3250);
FORCEPROP 2 LAST CDS_LIB mstr_standard
J 0
(-4550 3200);
PAINT ORANGE (-4550 3200);
DISPLAY INVISIBLE (-4550 3200);
FORCEPROP 1 LAST OFFPAGE TRUE
J 0
(-4225 3075);
DISPLAY 0.872340 (-4225 3075);
PAINT GREEN (-4225 3075);
DISPLAY INVISIBLE (-4225 3075);
FORCEPROP 1 LAST COMMENT_BODY TRUE
J 0
(-4425 3100);
DISPLAY 0.872340 (-4425 3100);
PAINT GREEN (-4425 3100);
DISPLAY INVISIBLE (-4425 3100);
FORCEADD P3V3_STBY..1
(-450 3850);
FORCEPROP 3 LASTPIN (-450 3800) SIG_NAME P3V3_STBY\g
J 0
(-440 3810);
DISPLAY 0.659574 (-440 3810);
PAINT MONO (-440 3810);
DISPLAY INVISIBLE (-440 3810);
FORCEPROP 1 LAST VOLTAGE 3.3V
J 0
(-495 3807);
DISPLAY 0.340426 (-495 3807);
PAINT SKYBLUE (-495 3807);
DISPLAY INVISIBLE (-495 3807);
FORCEPROP 2 LAST CDS_LIB mstr_symbols
J 0
(-450 3850);
PAINT ORANGE (-450 3850);
DISPLAY INVISIBLE (-450 3850);
FORCEPROP 1 LAST PATH I272
J 0
(-405 3852);
DISPLAY 0.340426 (-405 3852);
PAINT GREEN (-405 3852);
DISPLAY INVISIBLE (-405 3852);
FORCEPROP 1 LAST SIZE 1B
J 0
(-405 3872);
DISPLAY 0.340426 (-405 3872);
PAINT GREEN (-405 3872);
DISPLAY INVISIBLE (-405 3872);
FORCEPROP 1 LAST BODY_TYPE PLUMBING
J 0
(-495 3807);
DISPLAY 0.340426 (-495 3807);
PAINT GREEN (-495 3807);
DISPLAY INVISIBLE (-495 3807);
FORCEPROP 1 LAST HDL_POWER P3V3_STBY
J 0
(-750 3725);
DISPLAY 0.872340 (-750 3725);
PAINT ORANGE (-750 3725);
DISPLAY INVISIBLE (-750 3725);
FORCEADD CAP_A..1
(-450 3550);
FORCEPROP 1 LASTPIN (-450 3450) $PN 2
J 0
(-440 3430);
DISPLAY 0.617021 (-440 3430);
PAINT ORANGE (-440 3430);
FORCEPROP 1 LAST MATERIAL X7R
J 0
(-400 3450);
DISPLAY 0.617021 (-400 3450);
PAINT SKYBLUE (-400 3450);
FORCEPROP 1 LAST VOLTAGE 16V
J 0
(-400 3550);
DISPLAY 0.617021 (-400 3550);
PAINT SKYBLUE (-400 3550);
FORCEPROP 1 LAST TOLERANCE 10%
J 0
(-400 3500);
DISPLAY 0.617021 (-400 3500);
PAINT SKYBLUE (-400 3500);
FORCEPROP 1 LAST PACK_TYPE 0402V
J 0
(-400 3350);
DISPLAY 0.617021 (-400 3350);
PAINT SKYBLUE (-400 3350);
FORCEPROP 1 LAST PART_NUMBER A36096-030
J 0
(-400 3400);
DISPLAY 0.617021 (-400 3400);
PAINT BLUE (-400 3400);
FORCEPROP 1 LASTPIN (-450 3650) $PN 1
J 0
(-440 3630);
DISPLAY 0.617021 (-440 3630);
PAINT ORANGE (-440 3630);
FORCEPROP 1 LAST LOCATION C2T35
J 0
(-400 3650);
DISPLAY 0.617021 (-400 3650);
PAINT AQUA (-400 3650);
FORCEPROP 1 LAST VALUE 0.1UF
J 0
(-400 3600);
DISPLAY 0.617021 (-400 3600);
PAINT SKYBLUE (-400 3600);
FORCEPROP 2 LAST CDS_LIB dev_discrete
J 0
(-450 3550);
PAINT ORANGE (-450 3550);
DISPLAY INVISIBLE (-450 3550);
FORCEPROP 2 LAST CDS_LOCATION C2T35
J 0
(-400 3650);
DISPLAY 0.617021 (-400 3650);
PAINT AQUA (-400 3650);
DISPLAY INVISIBLE (-400 3650);
FORCEPROP 1 LAST PATH I273
J 0
(-400 3700);
DISPLAY 0.978723 (-400 3700);
PAINT WHITE (-400 3700);
DISPLAY INVISIBLE (-400 3700);
FORCEPROP 2 LAST CDS_SEC 1
J 0
(-400 3700);
PAINT ORANGE (-400 3700);
DISPLAY INVISIBLE (-400 3700);
FORCEPROP 2 LAST SEC 1
J 0
(-400 3700);
DISPLAY 0.680851 (-400 3700);
PAINT MONO (-400 3700);
DISPLAY INVISIBLE (-400 3700);
FORCEPROP 2 LAST ROOM BMC_MISC
J 0
(-400 3700);
DISPLAY 1.021277 (-400 3700);
PAINT ORANGE (-400 3700);
DISPLAY INVISIBLE (-400 3700);
FORCEPROP 2 LAST BOM_COST SM_CONTROLLER
J 0
(-400 3750);
DISPLAY 1.021277 (-400 3750);
PAINT ORANGE (-400 3750);
DISPLAY INVISIBLE (-400 3750);
FORCEPROP 2 LAST SEC_TYPE 0402V
J 0
(-400 3750);
DISPLAY 1.021277 (-400 3750);
PAINT ORANGE (-400 3750);
DISPLAY INVISIBLE (-400 3750);
FORCEADD GND..1
(-450 3250);
FORCEPROP 3 LASTPIN (-450 3300) SIG_NAME GND\g
J 0
(-440 3310);
DISPLAY 0.659574 (-440 3310);
PAINT MONO (-440 3310);
DISPLAY INVISIBLE (-440 3310);
FORCEPROP 2 LAST CDS_LIB mstr_symbols
J 0
(-450 3250);
PAINT ORANGE (-450 3250);
DISPLAY INVISIBLE (-450 3250);
FORCEPROP 1 LAST SIZE 1B
J 0
(-375 3200);
DISPLAY 0.872340 (-375 3200);
PAINT AQUA (-375 3200);
DISPLAY INVISIBLE (-375 3200);
FORCEPROP 1 LAST PATH I274
J 0
(-375 3250);
DISPLAY 0.872340 (-375 3250);
PAINT AQUA (-375 3250);
DISPLAY INVISIBLE (-375 3250);
FORCEPROP 1 LAST VOLTAGE 0.0V
J 0
(-495 3207);
DISPLAY 0.340426 (-495 3207);
PAINT SKYBLUE (-495 3207);
DISPLAY INVISIBLE (-495 3207);
FORCEPROP 1 LAST BODY_TYPE PLUMBING
J 0
(-495 3207);
DISPLAY 0.340426 (-495 3207);
PAINT GREEN (-495 3207);
DISPLAY INVISIBLE (-495 3207);
FORCEPROP 1 LAST HDL_POWER GND
J 0
(-450 3400);
DISPLAY 0.872340 (-450 3400);
PAINT GREEN (-450 3400);
DISPLAY INVISIBLE (-450 3400);
FORCEADD CAP_A..1
(-450 4450);
FORCEPROP 1 LASTPIN (-450 4350) $PN 2
J 0
(-440 4330);
DISPLAY 0.617021 (-440 4330);
PAINT ORANGE (-440 4330);
FORCEPROP 1 LAST MATERIAL X7R
J 0
(-400 4350);
DISPLAY 0.617021 (-400 4350);
PAINT SKYBLUE (-400 4350);
FORCEPROP 1 LASTPIN (-450 4550) $PN 1
J 0
(-440 4530);
DISPLAY 0.617021 (-440 4530);
PAINT ORANGE (-440 4530);
FORCEPROP 1 LAST VOLTAGE 16V
J 0
(-400 4450);
DISPLAY 0.617021 (-400 4450);
PAINT SKYBLUE (-400 4450);
FORCEPROP 1 LAST TOLERANCE 10%
J 0
(-400 4400);
DISPLAY 0.617021 (-400 4400);
PAINT SKYBLUE (-400 4400);
FORCEPROP 1 LAST PACK_TYPE 0402V
J 0
(-400 4250);
DISPLAY 0.617021 (-400 4250);
PAINT SKYBLUE (-400 4250);
FORCEPROP 1 LAST VALUE 0.1UF
J 0
(-400 4500);
DISPLAY 0.617021 (-400 4500);
PAINT SKYBLUE (-400 4500);
FORCEPROP 1 LAST PART_NUMBER A36096-030
J 0
(-400 4300);
DISPLAY 0.617021 (-400 4300);
PAINT BLUE (-400 4300);
FORCEPROP 1 LAST LOCATION C8F16
J 0
(-400 4550);
DISPLAY 0.617021 (-400 4550);
PAINT AQUA (-400 4550);
FORCEPROP 2 LAST CDS_LOCATION C8F16
J 0
(-400 4550);
DISPLAY 0.617021 (-400 4550);
PAINT AQUA (-400 4550);
DISPLAY INVISIBLE (-400 4550);
FORCEPROP 2 LAST CDS_LIB dev_discrete
J 0
(-450 4450);
PAINT ORANGE (-450 4450);
DISPLAY INVISIBLE (-450 4450);
FORCEPROP 1 LAST PATH I275
J 0
(-400 4600);
DISPLAY 0.978723 (-400 4600);
PAINT WHITE (-400 4600);
DISPLAY INVISIBLE (-400 4600);
FORCEPROP 2 LAST CDS_SEC 1
J 0
(-400 4600);
PAINT ORANGE (-400 4600);
DISPLAY INVISIBLE (-400 4600);
FORCEPROP 2 LAST SEC 1
J 0
(-400 4600);
DISPLAY 0.680851 (-400 4600);
PAINT MONO (-400 4600);
DISPLAY INVISIBLE (-400 4600);
FORCEPROP 2 LAST ROOM BMC_MISC
J 0
(-400 4600);
DISPLAY 1.021277 (-400 4600);
PAINT ORANGE (-400 4600);
DISPLAY INVISIBLE (-400 4600);
FORCEPROP 2 LAST BOM_COST SM_CONTROLLER
J 0
(-400 4650);
DISPLAY 1.021277 (-400 4650);
PAINT ORANGE (-400 4650);
DISPLAY INVISIBLE (-400 4650);
FORCEPROP 2 LAST SEC_TYPE 0402V
J 0
(-400 4650);
DISPLAY 1.021277 (-400 4650);
PAINT ORANGE (-400 4650);
DISPLAY INVISIBLE (-400 4650);
FORCEADD GND..1
(-450 4150);
FORCEPROP 3 LASTPIN (-450 4200) SIG_NAME GND\g
J 0
(-440 4210);
DISPLAY 0.659574 (-440 4210);
PAINT MONO (-440 4210);
DISPLAY INVISIBLE (-440 4210);
FORCEPROP 1 LAST VOLTAGE 0.0V
J 0
(-495 4107);
DISPLAY 0.340426 (-495 4107);
PAINT SKYBLUE (-495 4107);
DISPLAY INVISIBLE (-495 4107);
FORCEPROP 2 LAST CDS_LIB mstr_symbols
J 0
(-450 4150);
PAINT ORANGE (-450 4150);
DISPLAY INVISIBLE (-450 4150);
FORCEPROP 1 LAST PATH I276
J 0
(-375 4150);
DISPLAY 0.872340 (-375 4150);
PAINT AQUA (-375 4150);
DISPLAY INVISIBLE (-375 4150);
FORCEPROP 1 LAST SIZE 1B
J 0
(-375 4100);
DISPLAY 0.872340 (-375 4100);
PAINT AQUA (-375 4100);
DISPLAY INVISIBLE (-375 4100);
FORCEPROP 1 LAST BODY_TYPE PLUMBING
J 0
(-495 4107);
DISPLAY 0.340426 (-495 4107);
PAINT GREEN (-495 4107);
DISPLAY INVISIBLE (-495 4107);
FORCEPROP 1 LAST HDL_POWER GND
J 0
(-450 4300);
DISPLAY 0.872340 (-450 4300);
PAINT GREEN (-450 4300);
DISPLAY INVISIBLE (-450 4300);
FORCEADD P3V3_STBY..1
(-450 4750);
FORCEPROP 3 LASTPIN (-450 4700) SIG_NAME P3V3_STBY\g
J 0
(-440 4710);
DISPLAY 0.659574 (-440 4710);
PAINT MONO (-440 4710);
DISPLAY INVISIBLE (-440 4710);
FORCEPROP 2 LAST CDS_LIB mstr_symbols
J 0
(-450 4750);
PAINT ORANGE (-450 4750);
DISPLAY INVISIBLE (-450 4750);
FORCEPROP 1 LAST SIZE 1B
J 0
(-405 4772);
DISPLAY 0.340426 (-405 4772);
PAINT GREEN (-405 4772);
DISPLAY INVISIBLE (-405 4772);
FORCEPROP 1 LAST PATH I277
J 0
(-405 4752);
DISPLAY 0.340426 (-405 4752);
PAINT GREEN (-405 4752);
DISPLAY INVISIBLE (-405 4752);
FORCEPROP 1 LAST VOLTAGE 3.3V
J 0
(-495 4707);
DISPLAY 0.340426 (-495 4707);
PAINT SKYBLUE (-495 4707);
DISPLAY INVISIBLE (-495 4707);
FORCEPROP 1 LAST BODY_TYPE PLUMBING
J 0
(-495 4707);
DISPLAY 0.340426 (-495 4707);
PAINT GREEN (-495 4707);
DISPLAY INVISIBLE (-495 4707);
FORCEPROP 1 LAST HDL_POWER P3V3_STBY
J 0
(-750 4625);
DISPLAY 0.872340 (-750 4625);
PAINT ORANGE (-750 4625);
DISPLAY INVISIBLE (-750 4625);
FORCEADD OFFPAGE..2
(-5850 2350);
FORCEPROP 2 LAST $XR0 89 
J 0
(-5661 2350);
DISPLAY 0.638298 (-5661 2350);
PAINT MONO (-5661 2350);
FORCEPROP 2 LAST $XR1 157 
J 0
(-5571 2350);
DISPLAY 0.638298 (-5571 2350);
PAINT MONO (-5571 2350);
FORCEPROP 2 LAST $XR2 191 
J 0
(-5451 2350);
DISPLAY 0.638298 (-5451 2350);
PAINT MONO (-5451 2350);
FORCEPROP 2 LAST $XR3 120 
J 0
(-5331 2350);
DISPLAY 0.638298 (-5331 2350);
PAINT MONO (-5331 2350);
FORCEPROP 2 LAST CDS_LIB mstr_standard
J 0
(-5850 2350);
PAINT MONO (-5850 2350);
DISPLAY INVISIBLE (-5850 2350);
FORCEPROP 2 LAST PATH I278
J 0
(-5325 2400);
DISPLAY 1.021277 (-5325 2400);
PAINT ORANGE (-5325 2400);
DISPLAY INVISIBLE (-5325 2400);
FORCEPROP 1 LAST OFFPAGE TRUE
J 0
(-5525 2225);
DISPLAY 0.872340 (-5525 2225);
PAINT GREEN (-5525 2225);
DISPLAY INVISIBLE (-5525 2225);
FORCEPROP 1 LAST COMMENT_BODY TRUE
J 0
(-5895 2255);
DISPLAY 0.872340 (-5895 2255);
PAINT GREEN (-5895 2255);
DISPLAY INVISIBLE (-5895 2255);
FORCEADD RES..1
(-6600 2350);
FORCEPROP 1 LASTPIN (-6700 2350) $PN 1
J 0
(-6688 2362);
DISPLAY 0.617021 (-6688 2362);
PAINT ORANGE (-6688 2362);
FORCEPROP 1 LAST WATTAGE 1/16W
J 2
(-6625 2200);
DISPLAY 0.617021 (-6625 2200);
PAINT SKYBLUE (-6625 2200);
FORCEPROP 1 LAST VALUE 0.0
J 2
(-6625 2250);
DISPLAY 0.617021 (-6625 2250);
PAINT SKYBLUE (-6625 2250);
FORCEPROP 1 LAST TOLERANCE 5%
J 0
(-6600 2250);
DISPLAY 0.617021 (-6600 2250);
PAINT SKYBLUE (-6600 2250);
FORCEPROP 1 LAST MATERIAL EMPTY
J 0
(-6600 2200);
DISPLAY 0.617021 (-6600 2200);
PAINT RED (-6600 2200);
FORCEPROP 1 LASTPIN (-6500 2350) $PN 2
J 0
(-6538 2362);
DISPLAY 0.617021 (-6538 2362);
PAINT ORANGE (-6538 2362);
FORCEPROP 1 LAST LOCATION R8E11
J 0
(-6650 2400);
DISPLAY 0.617021 (-6650 2400);
PAINT AQUA (-6650 2400);
FORCEPROP 1 LAST PART_NUMBER G21497-005
J 0
(-6650 2450);
DISPLAY 0.617021 (-6650 2450);
PAINT BLUE (-6650 2450);
FORCEPROP 1 LAST PACK_TYPE 0402
J 0
(-6350 2200);
DISPLAY 0.617021 (-6350 2200);
PAINT SKYBLUE (-6350 2200);
FORCEPROP 2 LAST CDS_LIB mstr_discrete
J 0
(-6600 2350);
PAINT MONO (-6600 2350);
DISPLAY INVISIBLE (-6600 2350);
FORCEPROP 2 LAST CDS_LOCATION R8E11
J 0
(-6650 2400);
DISPLAY 0.617021 (-6650 2400);
PAINT AQUA (-6650 2400);
DISPLAY INVISIBLE (-6650 2400);
FORCEPROP 1 LAST PATH I279
J 0
(-6650 2500);
DISPLAY 0.978723 (-6650 2500);
PAINT WHITE (-6650 2500);
DISPLAY INVISIBLE (-6650 2500);
FORCEPROP 2 LAST SEC_TYPE 0402
J 0
(-6650 2550);
DISPLAY 1.021277 (-6650 2550);
PAINT ORANGE (-6650 2550);
DISPLAY INVISIBLE (-6650 2550);
FORCEPROP 2 LAST SEC 1
J 0
(-6650 2550);
PAINT MONO (-6650 2550);
DISPLAY INVISIBLE (-6650 2550);
FORCEPROP 0 LAST ROOM BMC_MISC
J 0
(-6650 2550);
DISPLAY 1.021277 (-6650 2550);
PAINT ORANGE (-6650 2550);
DISPLAY INVISIBLE (-6650 2550);
FORCEPROP 0 LAST BOM_COST SM_CONTROLLER
J 0
(-6650 2650);
DISPLAY 1.021277 (-6650 2650);
PAINT ORANGE (-6650 2650);
DISPLAY INVISIBLE (-6650 2650);
FORCEADD OFFPAGE..1
(-7450 2350);
FORCEPROP 2 LAST $XR0 94 
J 0
(-7701 2350);
DISPLAY 0.638298 (-7701 2350);
PAINT MONO (-7701 2350);
FORCEPROP 2 LAST $XR1 191 
J 0
(-7821 2350);
DISPLAY 0.638298 (-7821 2350);
PAINT MONO (-7821 2350);
FORCEPROP 2 LAST PATH I280
J 0
(-7650 2400);
DISPLAY 1.021277 (-7650 2400);
PAINT ORANGE (-7650 2400);
DISPLAY INVISIBLE (-7650 2400);
FORCEPROP 2 LAST CDS_LIB mstr_standard
J 0
(-7450 2350);
PAINT MONO (-7450 2350);
DISPLAY INVISIBLE (-7450 2350);
FORCEPROP 1 LAST OFFPAGE TRUE
J 0
(-7125 2225);
DISPLAY 0.872340 (-7125 2225);
PAINT GREEN (-7125 2225);
DISPLAY INVISIBLE (-7125 2225);
FORCEPROP 1 LAST COMMENT_BODY TRUE
J 0
(-7325 2250);
DISPLAY 0.872340 (-7325 2250);
PAINT GREEN (-7325 2250);
DISPLAY INVISIBLE (-7325 2250);
FORCEADD CONN3_C95678002..1
(-7575 3700);
FORCEPROP 1 LAST PART_NUMBER C95678-002
J 0
(-7625 3525);
DISPLAY 0.617021 (-7625 3525);
PAINT BLUE (-7625 3525);
FORCEPROP 2 LASTPIN (-7475 3650) $PN 3
J 0
(-7465 3660);
DISPLAY 0.617021 (-7465 3660);
PAINT ORANGE (-7465 3660);
FORCEPROP 2 LASTPIN (-7475 3700) $PN 2
J 0
(-7465 3710);
DISPLAY 0.617021 (-7465 3710);
PAINT ORANGE (-7465 3710);
FORCEPROP 2 LASTPIN (-7475 3750) $PN 1
J 0
(-7465 3760);
DISPLAY 0.617021 (-7465 3760);
PAINT ORANGE (-7465 3760);
FORCEPROP 1 LAST MATERIAL CONN
J 0
(-7625 3850);
DISPLAY 0.617021 (-7625 3850);
PAINT SKYBLUE (-7625 3850);
FORCEPROP 1 LAST LOCATION J9B2
J 0
(-7625 3900);
DISPLAY 0.617021 (-7625 3900);
PAINT AQUA (-7625 3900);
FORCEPROP 2 LAST CDS_LIB mstr_conn
J 0
(-7575 3700);
PAINT ORANGE (-7575 3700);
DISPLAY INVISIBLE (-7575 3700);
FORCEPROP 2 LAST SEC_TYPE PIP
J 0
(-7625 3950);
DISPLAY 1.021277 (-7625 3950);
PAINT ORANGE (-7625 3950);
DISPLAY INVISIBLE (-7625 3950);
FORCEPROP 2 LAST SEC 1
J 0
(-7625 3950);
DISPLAY 0.680851 (-7625 3950);
PAINT MONO (-7625 3950);
DISPLAY INVISIBLE (-7625 3950);
FORCEPROP 2 LAST CDS_LOCATION J9B2
J 0
(-7625 3900);
DISPLAY 0.617021 (-7625 3900);
PAINT AQUA (-7625 3900);
DISPLAY INVISIBLE (-7625 3900);
FORCEPROP 0 LAST ROOM DEBUG
J 0
(-7625 4000);
DISPLAY 1.021277 (-7625 4000);
PAINT ORANGE (-7625 4000);
DISPLAY INVISIBLE (-7625 4000);
FORCEPROP 1 LAST PACK_TYPE PIP
J 0
(-7625 3950);
DISPLAY 0.978723 (-7625 3950);
PAINT SKYBLUE (-7625 3950);
DISPLAY INVISIBLE (-7625 3950);
FORCEPROP 1 LAST PATH I281
J 0
(-7175 3850);
DISPLAY 0.978723 (-7175 3850);
PAINT BLUE (-7175 3850);
DISPLAY INVISIBLE (-7175 3850);
FORCEPROP 0 LAST BOM_COST DEBUG
J 0
(-7625 4100);
DISPLAY 1.021277 (-7625 4100);
PAINT ORANGE (-7625 4100);
DISPLAY INVISIBLE (-7625 4100);
FORCEADD GND..1
(-7275 3475);
FORCEPROP 3 LASTPIN (-7275 3525) SIG_NAME GND\g
J 0
(-7265 3535);
DISPLAY 0.659574 (-7265 3535);
PAINT MONO (-7265 3535);
DISPLAY INVISIBLE (-7265 3535);
FORCEPROP 2 LAST CDS_LIB mstr_symbols
J 0
(-7275 3475);
PAINT ORANGE (-7275 3475);
DISPLAY INVISIBLE (-7275 3475);
FORCEPROP 1 LAST SIZE 1B
J 0
(-7200 3425);
DISPLAY 0.872340 (-7200 3425);
PAINT AQUA (-7200 3425);
DISPLAY INVISIBLE (-7200 3425);
FORCEPROP 1 LAST PATH I282
J 0
(-7200 3475);
DISPLAY 0.872340 (-7200 3475);
PAINT AQUA (-7200 3475);
DISPLAY INVISIBLE (-7200 3475);
FORCEPROP 1 LAST VOLTAGE 0.0V
J 0
(-7320 3432);
DISPLAY 0.340426 (-7320 3432);
PAINT SKYBLUE (-7320 3432);
DISPLAY INVISIBLE (-7320 3432);
FORCEPROP 1 LAST BODY_TYPE PLUMBING
J 0
(-7320 3432);
DISPLAY 0.340426 (-7320 3432);
PAINT GREEN (-7320 3432);
DISPLAY INVISIBLE (-7320 3432);
FORCEPROP 1 LAST HDL_POWER GND
J 0
(-7275 3625);
DISPLAY 0.872340 (-7275 3625);
PAINT GREEN (-7275 3625);
DISPLAY INVISIBLE (-7275 3625);
FORCEADD OFFPAGE..3
(-6500 3750);
FORCEPROP 2 LAST $XR0 138 
J 0
(-6286 3750);
DISPLAY 0.638298 (-6286 3750);
PAINT MONO (-6286 3750);
FORCEPROP 2 LAST $XR1 159 
J 0
(-6166 3750);
DISPLAY 0.638298 (-6166 3750);
PAINT MONO (-6166 3750);
FORCEPROP 2 LAST CDS_LIB mstr_standard
J 0
(-6500 3750);
PAINT ORANGE (-6500 3750);
DISPLAY INVISIBLE (-6500 3750);
FORCEPROP 2 LAST PATH I283
J 0
(-6325 3825);
DISPLAY 1.021277 (-6325 3825);
PAINT ORANGE (-6325 3825);
DISPLAY INVISIBLE (-6325 3825);
FORCEPROP 1 LAST OFFPAGE TRUE
J 0
(-6175 3625);
DISPLAY 0.872340 (-6175 3625);
PAINT GREEN (-6175 3625);
DISPLAY INVISIBLE (-6175 3625);
FORCEPROP 1 LAST COMMENT_BODY TRUE
J 0
(-6550 3650);
DISPLAY 0.872340 (-6550 3650);
PAINT GREEN (-6550 3650);
DISPLAY INVISIBLE (-6550 3650);
FORCEADD OFFPAGE..4
(-6500 3650);
FORCEPROP 2 LAST $XR0 138 
J 0
(-6314 3650);
DISPLAY 0.638298 (-6314 3650);
PAINT MONO (-6314 3650);
FORCEPROP 2 LAST $XR1 159 
J 0
(-6194 3650);
DISPLAY 0.638298 (-6194 3650);
PAINT MONO (-6194 3650);
FORCEPROP 2 LAST CDS_LIB mstr_standard
J 0
(-6500 3650);
PAINT ORANGE (-6500 3650);
DISPLAY INVISIBLE (-6500 3650);
FORCEPROP 2 LAST PATH I284
J 0
(-6325 3725);
DISPLAY 1.021277 (-6325 3725);
PAINT ORANGE (-6325 3725);
DISPLAY INVISIBLE (-6325 3725);
FORCEPROP 1 LAST OFFPAGE TRUE
J 0
(-6175 3525);
DISPLAY 0.872340 (-6175 3525);
PAINT GREEN (-6175 3525);
DISPLAY INVISIBLE (-6175 3525);
FORCEPROP 1 LAST COMMENT_BODY TRUE
J 0
(-6525 3550);
DISPLAY 0.872340 (-6525 3550);
PAINT GREEN (-6525 3550);
DISPLAY INVISIBLE (-6525 3550);
FORCEADD CONN3_C95678002..1
(-7600 4475);
FORCEPROP 2 LASTPIN (-7500 4425) $PN 3
J 0
(-7490 4435);
DISPLAY 0.617021 (-7490 4435);
PAINT ORANGE (-7490 4435);
FORCEPROP 2 LASTPIN (-7500 4475) $PN 2
J 0
(-7490 4485);
DISPLAY 0.617021 (-7490 4485);
PAINT ORANGE (-7490 4485);
FORCEPROP 1 LAST MATERIAL CONN
J 0
(-7650 4625);
DISPLAY 0.617021 (-7650 4625);
PAINT SKYBLUE (-7650 4625);
FORCEPROP 1 LAST LOCATION J8C1
J 0
(-7650 4675);
DISPLAY 0.617021 (-7650 4675);
PAINT AQUA (-7650 4675);
FORCEPROP 1 LAST PART_NUMBER C95678-002
J 0
(-7650 4300);
DISPLAY 0.617021 (-7650 4300);
PAINT BLUE (-7650 4300);
FORCEPROP 2 LASTPIN (-7500 4525) $PN 1
J 0
(-7490 4535);
DISPLAY 0.617021 (-7490 4535);
PAINT ORANGE (-7490 4535);
FORCEPROP 2 LAST CDS_LIB mstr_conn
J 0
(-7600 4475);
PAINT ORANGE (-7600 4475);
DISPLAY INVISIBLE (-7600 4475);
FORCEPROP 2 LAST SEC_TYPE PIP
J 0
(-7650 4725);
DISPLAY 1.021277 (-7650 4725);
PAINT ORANGE (-7650 4725);
DISPLAY INVISIBLE (-7650 4725);
FORCEPROP 0 LAST BOM_COST DEBUG
J 0
(-7650 4875);
DISPLAY 1.021277 (-7650 4875);
PAINT ORANGE (-7650 4875);
DISPLAY INVISIBLE (-7650 4875);
FORCEPROP 2 LAST SEC 1
J 0
(-7650 4725);
DISPLAY 0.680851 (-7650 4725);
PAINT MONO (-7650 4725);
DISPLAY INVISIBLE (-7650 4725);
FORCEPROP 2 LAST CDS_LOCATION J8C1
J 0
(-7650 4675);
DISPLAY 0.617021 (-7650 4675);
PAINT AQUA (-7650 4675);
DISPLAY INVISIBLE (-7650 4675);
FORCEPROP 1 LAST PATH I285
J 0
(-7200 4625);
DISPLAY 0.978723 (-7200 4625);
PAINT BLUE (-7200 4625);
DISPLAY INVISIBLE (-7200 4625);
FORCEPROP 0 LAST ROOM DEBUG
J 0
(-7650 4775);
DISPLAY 1.021277 (-7650 4775);
PAINT ORANGE (-7650 4775);
DISPLAY INVISIBLE (-7650 4775);
FORCEPROP 1 LAST PACK_TYPE PIP
J 0
(-7650 4725);
DISPLAY 0.978723 (-7650 4725);
PAINT SKYBLUE (-7650 4725);
DISPLAY INVISIBLE (-7650 4725);
FORCEADD OFFPAGE..4
(-6525 4425);
FORCEPROP 2 LAST $XR0 138 
J 0
(-6339 4425);
DISPLAY 0.638298 (-6339 4425);
PAINT MONO (-6339 4425);
FORCEPROP 2 LAST $XR1 159 
J 0
(-6219 4425);
DISPLAY 0.638298 (-6219 4425);
PAINT MONO (-6219 4425);
FORCEPROP 2 LAST $XR2 101 
J 0
(-6099 4425);
DISPLAY 0.638298 (-6099 4425);
PAINT MONO (-6099 4425);
FORCEPROP 2 LAST $XR3 102 
J 0
(-5979 4425);
DISPLAY 0.638298 (-5979 4425);
PAINT MONO (-5979 4425);
FORCEPROP 2 LAST $XR4 111 
J 0
(-5859 4425);
DISPLAY 0.638298 (-5859 4425);
PAINT MONO (-5859 4425);
FORCEPROP 2 LAST $XR5 247 
J 0
(-5859 4425);
DISPLAY 0.638298 (-5859 4425);
PAINT MONO (-5859 4425);
FORCEPROP 2 LAST CDS_LIB mstr_standard
J 0
(-6525 4425);
PAINT ORANGE (-6525 4425);
DISPLAY INVISIBLE (-6525 4425);
FORCEPROP 2 LAST PATH I286
J 0
(-6350 4500);
DISPLAY 1.021277 (-6350 4500);
PAINT ORANGE (-6350 4500);
DISPLAY INVISIBLE (-6350 4500);
FORCEPROP 1 LAST OFFPAGE TRUE
J 0
(-6200 4300);
DISPLAY 0.872340 (-6200 4300);
PAINT GREEN (-6200 4300);
DISPLAY INVISIBLE (-6200 4300);
FORCEPROP 1 LAST COMMENT_BODY TRUE
J 0
(-6550 4325);
DISPLAY 0.872340 (-6550 4325);
PAINT GREEN (-6550 4325);
DISPLAY INVISIBLE (-6550 4325);
FORCEADD OFFPAGE..3
(-6525 4525);
FORCEPROP 2 LAST $XR0 101 
J 0
(-6311 4525);
DISPLAY 0.638298 (-6311 4525);
PAINT MONO (-6311 4525);
FORCEPROP 2 LAST $XR1 102 
J 0
(-6191 4525);
DISPLAY 0.638298 (-6191 4525);
PAINT MONO (-6191 4525);
FORCEPROP 2 LAST $XR2 111 
J 0
(-6071 4525);
DISPLAY 0.638298 (-6071 4525);
PAINT MONO (-6071 4525);
FORCEPROP 2 LAST $XR3 138 
J 0
(-5951 4525);
DISPLAY 0.638298 (-5951 4525);
PAINT MONO (-5951 4525);
FORCEPROP 2 LAST $XR4 159 
J 0
(-5831 4525);
DISPLAY 0.638298 (-5831 4525);
PAINT MONO (-5831 4525);
FORCEPROP 2 LAST $XR5 247 
J 0
(-5831 4525);
DISPLAY 0.638298 (-5831 4525);
PAINT MONO (-5831 4525);
FORCEPROP 2 LAST CDS_LIB mstr_standard
J 0
(-6525 4525);
PAINT ORANGE (-6525 4525);
DISPLAY INVISIBLE (-6525 4525);
FORCEPROP 2 LAST PATH I287
J 0
(-6325 4600);
DISPLAY 1.021277 (-6325 4600);
PAINT ORANGE (-6325 4600);
DISPLAY INVISIBLE (-6325 4600);
FORCEPROP 1 LAST OFFPAGE TRUE
J 0
(-6200 4400);
DISPLAY 0.872340 (-6200 4400);
PAINT GREEN (-6200 4400);
DISPLAY INVISIBLE (-6200 4400);
FORCEPROP 1 LAST COMMENT_BODY TRUE
J 0
(-6575 4425);
DISPLAY 0.872340 (-6575 4425);
PAINT GREEN (-6575 4425);
DISPLAY INVISIBLE (-6575 4425);
FORCEADD RES..1
(-1700 4150);
FORCEPROP 1 LAST VALUE 49.9
J 2
(-1875 4250);
DISPLAY 0.617021 (-1875 4250);
PAINT SKYBLUE (-1875 4250);
FORCEPROP 1 LAST TOLERANCE 1%
J 0
(-1850 4250);
DISPLAY 0.617021 (-1850 4250);
PAINT SKYBLUE (-1850 4250);
FORCEPROP 1 LASTPIN (-1800 4150) $PN 1
J 0
(-1788 4162);
DISPLAY 0.617021 (-1788 4162);
PAINT ORANGE (-1788 4162);
FORCEPROP 1 LAST LOCATION R2T18
J 0
(-1750 4200);
DISPLAY 0.617021 (-1750 4200);
PAINT AQUA (-1750 4200);
FORCEPROP 1 LASTPIN (-1600 4150) $PN 2
J 0
(-1638 4162);
DISPLAY 0.617021 (-1638 4162);
PAINT ORANGE (-1638 4162);
FORCEPROP 1 LAST PART_NUMBER G21796-047
J 0
(-1750 4250);
DISPLAY 0.617021 (-1750 4250);
PAINT BLUE (-1750 4250);
FORCEPROP 1 LAST MATERIAL CHIP
J 0
(-1350 4250);
DISPLAY 0.617021 (-1350 4250);
PAINT SKYBLUE (-1350 4250);
FORCEPROP 1 LAST PACK_TYPE 0402
J 0
(-1475 4250);
DISPLAY 0.617021 (-1475 4250);
PAINT SKYBLUE (-1475 4250);
FORCEPROP 1 LAST WATTAGE 1/16W
J 2
(-1725 4000);
DISPLAY 0.978723 (-1725 4000);
PAINT SKYBLUE (-1725 4000);
DISPLAY INVISIBLE (-1725 4000);
FORCEPROP 2 LAST CDS_LIB mstr_discrete
J 0
(-1700 4150);
PAINT ORANGE (-1700 4150);
DISPLAY INVISIBLE (-1700 4150);
FORCEPROP 1 LAST PATH I288
J 0
(-1750 4300);
DISPLAY 0.978723 (-1750 4300);
PAINT WHITE (-1750 4300);
DISPLAY INVISIBLE (-1750 4300);
FORCEPROP 2 LAST CDS_LOCATION R2T18
J 0
(-1750 4200);
DISPLAY 0.617021 (-1750 4200);
PAINT AQUA (-1750 4200);
DISPLAY INVISIBLE (-1750 4200);
FORCEPROP 2 LAST SEC 1
J 0
(-1750 4350);
PAINT MONO (-1750 4350);
DISPLAY INVISIBLE (-1750 4350);
FORCEPROP 2 LAST SEC_TYPE 0402
J 0
(-1750 4350);
DISPLAY 1.021277 (-1750 4350);
PAINT ORANGE (-1750 4350);
DISPLAY INVISIBLE (-1750 4350);
FORCEPROP 0 LAST BOM_COST SM_CONTROLLER
J 0
(-1350 4450);
DISPLAY 1.021277 (-1350 4450);
PAINT ORANGE (-1350 4450);
DISPLAY INVISIBLE (-1350 4450);
FORCEPROP 0 LAST ROOM BMC_MISC
J 0
(-1350 4350);
DISPLAY 1.021277 (-1350 4350);
PAINT ORANGE (-1350 4350);
DISPLAY INVISIBLE (-1350 4350);
FORCEADD RES..1
R 6
(-1700 4100);
FORCEPROP 1 LASTPIN (-1600 4100) $PN 2
J 0
(-1638 4051);
DISPLAY 0.617021 (-1638 4051);
PAINT ORANGE (-1638 4051);
FORCEPROP 1 LASTPIN (-1800 4100) $PN 1
J 0
(-1788 4051);
DISPLAY 0.617021 (-1788 4051);
PAINT ORANGE (-1788 4051);
FORCEPROP 1 LAST TOLERANCE 1%
J 0
(-1850 3971);
DISPLAY 0.617021 (-1850 3971);
PAINT SKYBLUE (-1850 3971);
FORCEPROP 1 LAST VALUE 33.2
J 2
(-1875 3971);
DISPLAY 0.617021 (-1875 3971);
PAINT SKYBLUE (-1875 3971);
FORCEPROP 1 LAST LOCATION R2T28
J 0
(-1750 4021);
DISPLAY 0.617021 (-1750 4021);
PAINT AQUA (-1750 4021);
FORCEPROP 1 LAST PART_NUMBER G21796-074
J 0
(-1750 3971);
DISPLAY 0.617021 (-1750 3971);
PAINT BLUE (-1750 3971);
FORCEPROP 1 LAST MATERIAL CHIP
J 0
(-1350 3971);
DISPLAY 0.617021 (-1350 3971);
PAINT SKYBLUE (-1350 3971);
FORCEPROP 1 LAST PACK_TYPE 0402
J 0
(-1475 3971);
DISPLAY 0.617021 (-1475 3971);
PAINT SKYBLUE (-1475 3971);
FORCEPROP 2 LAST CDS_LIB mstr_discrete
J 0
(-1700 4053);
PAINT ORANGE (-1700 4053);
DISPLAY INVISIBLE (-1700 4053);
FORCEPROP 2 LAST SEC_TYPE 0402
J 0
(-1750 4050);
DISPLAY 1.021277 (-1750 4050);
PAINT ORANGE (-1750 4050);
DISPLAY INVISIBLE (-1750 4050);
FORCEPROP 2 LAST SEC 1
J 0
(-1750 4050);
PAINT MONO (-1750 4050);
DISPLAY INVISIBLE (-1750 4050);
FORCEPROP 2 LAST CDS_LOCATION R2T28
J 0
(-1750 4021);
DISPLAY 0.617021 (-1750 4021);
PAINT AQUA (-1750 4021);
DISPLAY INVISIBLE (-1750 4021);
FORCEPROP 1 LAST PATH I289
J 0
(-1750 3904);
DISPLAY 0.978723 (-1750 3904);
PAINT WHITE (-1750 3904);
DISPLAY INVISIBLE (-1750 3904);
FORCEPROP 0 LAST BOM_COST SM_CONTROLLER
J 0
(-1350 3752);
DISPLAY 1.021277 (-1350 3752);
PAINT ORANGE (-1350 3752);
DISPLAY INVISIBLE (-1350 3752);
FORCEPROP 0 LAST ROOM BMC_MISC
J 0
(-1350 3852);
DISPLAY 1.021277 (-1350 3852);
PAINT ORANGE (-1350 3852);
DISPLAY INVISIBLE (-1350 3852);
FORCEPROP 1 LAST WATTAGE 1/16W
J 2
(-1725 4204);
DISPLAY 0.978723 (-1725 4204);
PAINT SKYBLUE (-1725 4204);
DISPLAY INVISIBLE (-1725 4204);
FORCEADD OFFPAGE..1
(-4075 1550);
FORCEPROP 2 LAST $XR0 119 
J 0
(-4357 1550);
DISPLAY 0.638298 (-4357 1550);
PAINT MONO (-4357 1550);
FORCEPROP 2 LAST $XR1 144 
J 0
(-4477 1550);
DISPLAY 0.638298 (-4477 1550);
PAINT MONO (-4477 1550);
FORCEPROP 2 LAST PATH I296
J 0
(-4025 1625);
DISPLAY 1.021277 (-4025 1625);
PAINT ORANGE (-4025 1625);
DISPLAY INVISIBLE (-4025 1625);
FORCEPROP 2 LAST CDS_LIB mstr_standard
J 0
(-4075 1550);
PAINT ORANGE (-4075 1550);
DISPLAY INVISIBLE (-4075 1550);
FORCEPROP 1 LAST OFFPAGE TRUE
J 0
(-3750 1425);
DISPLAY 0.872340 (-3750 1425);
PAINT GREEN (-3750 1425);
DISPLAY INVISIBLE (-3750 1425);
FORCEPROP 1 LAST COMMENT_BODY TRUE
J 0
(-3950 1450);
DISPLAY 0.872340 (-3950 1450);
PAINT GREEN (-3950 1450);
DISPLAY INVISIBLE (-3950 1450);
FORCEADD OFFPAGE..2
(-1825 1825);
FORCEPROP 2 LAST $XR0 90 
J 0
(-1636 1825);
DISPLAY 0.638298 (-1636 1825);
PAINT MONO (-1636 1825);
FORCEPROP 2 LAST $XR1 21 
J 0
(-1546 1825);
DISPLAY 0.638298 (-1546 1825);
PAINT MONO (-1546 1825);
FORCEPROP 2 LAST CDS_LIB mstr_standard
J 0
(-1825 1825);
PAINT ORANGE (-1825 1825);
DISPLAY INVISIBLE (-1825 1825);
FORCEPROP 2 LAST PATH I297
J 0
(-1775 1900);
DISPLAY 1.021277 (-1775 1900);
PAINT ORANGE (-1775 1900);
DISPLAY INVISIBLE (-1775 1900);
FORCEPROP 1 LAST OFFPAGE TRUE
J 0
(-1500 1700);
DISPLAY 0.872340 (-1500 1700);
PAINT GREEN (-1500 1700);
DISPLAY INVISIBLE (-1500 1700);
FORCEPROP 1 LAST COMMENT_BODY TRUE
J 0
(-1870 1730);
DISPLAY 0.872340 (-1870 1730);
PAINT GREEN (-1870 1730);
DISPLAY INVISIBLE (-1870 1730);
FORCEADD OFFPAGE..2
(-1825 1550);
FORCEPROP 2 LAST $XR0 90 
J 0
(-1636 1550);
DISPLAY 0.638298 (-1636 1550);
PAINT MONO (-1636 1550);
FORCEPROP 2 LAST $XR1 55 
J 0
(-1546 1550);
DISPLAY 0.638298 (-1546 1550);
PAINT MONO (-1546 1550);
FORCEPROP 2 LAST CDS_LIB mstr_standard
J 0
(-1825 1550);
PAINT ORANGE (-1825 1550);
DISPLAY INVISIBLE (-1825 1550);
FORCEPROP 2 LAST PATH I298
J 0
(-1775 1625);
DISPLAY 1.021277 (-1775 1625);
PAINT ORANGE (-1775 1625);
DISPLAY INVISIBLE (-1775 1625);
FORCEPROP 1 LAST OFFPAGE TRUE
J 0
(-1500 1425);
DISPLAY 0.872340 (-1500 1425);
PAINT GREEN (-1500 1425);
DISPLAY INVISIBLE (-1500 1425);
FORCEPROP 1 LAST COMMENT_BODY TRUE
J 0
(-1870 1455);
DISPLAY 0.872340 (-1870 1455);
PAINT GREEN (-1870 1455);
DISPLAY INVISIBLE (-1870 1455);
FORCEADD RES..1
(-2900 1825);
FORCEPROP 1 LAST VALUE 0.0
J 2
(-2950 1750);
DISPLAY 0.617021 (-2950 1750);
PAINT SKYBLUE (-2950 1750);
FORCEPROP 1 LASTPIN (-3000 1825) $PN 1
J 0
(-2988 1837);
DISPLAY 0.617021 (-2988 1837);
PAINT ORANGE (-2988 1837);
FORCEPROP 1 LASTPIN (-2800 1825) $PN 2
J 0
(-2838 1837);
DISPLAY 0.617021 (-2838 1837);
PAINT ORANGE (-2838 1837);
FORCEPROP 1 LAST LOCATION R6D16
J 0
(-2950 1900);
DISPLAY 0.617021 (-2950 1900);
PAINT AQUA (-2950 1900);
FORCEPROP 1 LAST PACK_TYPE 0402
J 0
(-2800 1750);
DISPLAY 0.617021 (-2800 1750);
PAINT SKYBLUE (-2800 1750);
FORCEPROP 1 LAST MATERIAL EMPTY
J 0
(-2675 1750);
DISPLAY 0.617021 (-2675 1750);
PAINT RED (-2675 1750);
FORCEPROP 1 LAST PART_NUMBER G21497-005
J 0
(-2800 1850);
DISPLAY 0.617021 (-2800 1850);
PAINT BLUE (-2800 1850);
FORCEPROP 1 LAST WATTAGE 1/16W
J 2
(-2925 1675);
DISPLAY 0.978723 (-2925 1675);
PAINT SKYBLUE (-2925 1675);
DISPLAY INVISIBLE (-2925 1675);
FORCEPROP 1 LAST TOLERANCE 5%
J 0
(-2900 1725);
DISPLAY 0.978723 (-2900 1725);
PAINT SKYBLUE (-2900 1725);
DISPLAY INVISIBLE (-2900 1725);
FORCEPROP 1 LAST PATH I299
J 0
(-2950 1975);
DISPLAY 0.978723 (-2950 1975);
PAINT WHITE (-2950 1975);
DISPLAY INVISIBLE (-2950 1975);
FORCEPROP 2 LAST CDS_LIB mstr_discrete
J 0
(-2900 1825);
PAINT ORANGE (-2900 1825);
DISPLAY INVISIBLE (-2900 1825);
FORCEPROP 0 LAST ROOM BMC_MISC
J 0
(-2800 1950);
DISPLAY 1.021277 (-2800 1950);
PAINT ORANGE (-2800 1950);
DISPLAY INVISIBLE (-2800 1950);
FORCEPROP 2 LAST SEC_TYPE 0402
J 0
(-2950 2025);
DISPLAY 1.021277 (-2950 2025);
PAINT ORANGE (-2950 2025);
DISPLAY INVISIBLE (-2950 2025);
FORCEPROP 2 LAST SEC 1
J 0
(-2950 2025);
DISPLAY 0.680851 (-2950 2025);
PAINT MONO (-2950 2025);
DISPLAY INVISIBLE (-2950 2025);
FORCEPROP 0 LAST BOM_COST SM_CONTROLLER
J 0
(-2800 2050);
DISPLAY 1.021277 (-2800 2050);
PAINT ORANGE (-2800 2050);
DISPLAY INVISIBLE (-2800 2050);
FORCEADD RES..1
(-2900 1550);
FORCEPROP 1 LAST VALUE 0.0
J 2
(-2950 1475);
DISPLAY 0.617021 (-2950 1475);
PAINT SKYBLUE (-2950 1475);
FORCEPROP 1 LAST PACK_TYPE 0402
J 0
(-2800 1475);
DISPLAY 0.617021 (-2800 1475);
PAINT SKYBLUE (-2800 1475);
FORCEPROP 1 LASTPIN (-3000 1550) $PN 1
J 0
(-2988 1562);
DISPLAY 0.617021 (-2988 1562);
PAINT ORANGE (-2988 1562);
FORCEPROP 1 LAST LOCATION R3D31
J 0
(-2950 1625);
DISPLAY 0.617021 (-2950 1625);
PAINT AQUA (-2950 1625);
FORCEPROP 1 LASTPIN (-2800 1550) $PN 2
J 0
(-2838 1562);
DISPLAY 0.617021 (-2838 1562);
PAINT ORANGE (-2838 1562);
FORCEPROP 1 LAST MATERIAL EMPTY
J 0
(-2675 1475);
DISPLAY 0.617021 (-2675 1475);
PAINT RED (-2675 1475);
FORCEPROP 1 LAST PART_NUMBER G21497-005
J 0
(-2800 1575);
DISPLAY 0.617021 (-2800 1575);
PAINT BLUE (-2800 1575);
FORCEPROP 1 LAST WATTAGE 1/16W
J 2
(-2925 1400);
DISPLAY 0.978723 (-2925 1400);
PAINT SKYBLUE (-2925 1400);
DISPLAY INVISIBLE (-2925 1400);
FORCEPROP 1 LAST TOLERANCE 5%
J 0
(-2900 1450);
DISPLAY 0.978723 (-2900 1450);
PAINT SKYBLUE (-2900 1450);
DISPLAY INVISIBLE (-2900 1450);
FORCEPROP 2 LAST SEC 1
J 0
(-2950 1750);
DISPLAY 0.680851 (-2950 1750);
PAINT MONO (-2950 1750);
DISPLAY INVISIBLE (-2950 1750);
FORCEPROP 1 LAST PATH I300
J 0
(-2950 1700);
DISPLAY 0.978723 (-2950 1700);
PAINT WHITE (-2950 1700);
DISPLAY INVISIBLE (-2950 1700);
FORCEPROP 2 LAST CDS_LIB mstr_discrete
J 0
(-2900 1550);
PAINT ORANGE (-2900 1550);
DISPLAY INVISIBLE (-2900 1550);
FORCEPROP 2 LAST SEC_TYPE 0402
J 0
(-2950 1750);
DISPLAY 1.021277 (-2950 1750);
PAINT ORANGE (-2950 1750);
DISPLAY INVISIBLE (-2950 1750);
FORCEPROP 0 LAST ROOM BMC_MISC
J 0
(-2800 1675);
DISPLAY 1.021277 (-2800 1675);
PAINT ORANGE (-2800 1675);
DISPLAY INVISIBLE (-2800 1675);
FORCEPROP 0 LAST BOM_COST SM_CONTROLLER
J 0
(-2800 1775);
DISPLAY 1.021277 (-2800 1775);
PAINT ORANGE (-2800 1775);
DISPLAY INVISIBLE (-2800 1775);
FORCEADD RES..1
(-4000 975);
FORCEPROP 1 LAST VALUE 1.00K
J 2
(-4050 900);
DISPLAY 0.617021 (-4050 900);
PAINT SKYBLUE (-4050 900);
FORCEPROP 1 LASTPIN (-4100 975) $PN 1
J 0
(-4088 987);
DISPLAY 0.617021 (-4088 987);
PAINT ORANGE (-4088 987);
FORCEPROP 1 LASTPIN (-3900 975) $PN 2
J 0
(-3938 987);
DISPLAY 0.617021 (-3938 987);
PAINT ORANGE (-3938 987);
FORCEPROP 1 LAST TOLERANCE 1%
J 0
(-3925 900);
DISPLAY 0.617021 (-3925 900);
PAINT SKYBLUE (-3925 900);
FORCEPROP 1 LAST WATTAGE 1/16W
J 2
(-3525 900);
DISPLAY 0.617021 (-3525 900);
PAINT SKYBLUE (-3525 900);
FORCEPROP 1 LAST PART_NUMBER G21796-026
J 0
(-3875 1000);
DISPLAY 0.617021 (-3875 1000);
PAINT BLUE (-3875 1000);
FORCEPROP 1 LAST LOCATION R6N14
J 0
(-4050 1025);
DISPLAY 0.617021 (-4050 1025);
PAINT AQUA (-4050 1025);
FORCEPROP 1 LAST MATERIAL CHIP
J 0
(-4000 825);
DISPLAY 0.978723 (-4000 825);
PAINT SKYBLUE (-4000 825);
DISPLAY INVISIBLE (-4000 825);
FORCEPROP 2 LAST CDS_LIB mstr_discrete
J 0
(-4000 975);
PAINT ORANGE (-4000 975);
DISPLAY INVISIBLE (-4000 975);
FORCEPROP 1 LAST PACK_TYPE 0402
J 0
(-3750 825);
DISPLAY 0.978723 (-3750 825);
PAINT SKYBLUE (-3750 825);
DISPLAY INVISIBLE (-3750 825);
FORCEPROP 0 LAST ROOM CPU0
J 0
(-4050 1125);
DISPLAY 1.021277 (-4050 1125);
PAINT ORANGE (-4050 1125);
DISPLAY INVISIBLE (-4050 1125);
FORCEPROP 1 LAST PATH I302
J 0
(-4050 1125);
DISPLAY 0.978723 (-4050 1125);
PAINT WHITE (-4050 1125);
DISPLAY INVISIBLE (-4050 1125);
FORCEPROP 2 LAST SEC 1
J 0
(-4050 1175);
DISPLAY 0.680851 (-4050 1175);
PAINT MONO (-4050 1175);
DISPLAY INVISIBLE (-4050 1175);
FORCEPROP 2 LAST SEC_TYPE 0402
J 0
(-4050 1175);
DISPLAY 1.021277 (-4050 1175);
PAINT ORANGE (-4050 1175);
DISPLAY INVISIBLE (-4050 1175);
FORCEADD RES..1
(-4000 775);
FORCEPROP 1 LAST VALUE 1.00K
J 2
(-4050 700);
DISPLAY 0.617021 (-4050 700);
PAINT SKYBLUE (-4050 700);
FORCEPROP 1 LAST TOLERANCE 1%
J 0
(-3925 700);
DISPLAY 0.617021 (-3925 700);
PAINT SKYBLUE (-3925 700);
FORCEPROP 1 LASTPIN (-4100 775) $PN 1
J 0
(-4088 787);
DISPLAY 0.617021 (-4088 787);
PAINT ORANGE (-4088 787);
FORCEPROP 1 LAST LOCATION R6N13
J 0
(-4050 825);
DISPLAY 0.617021 (-4050 825);
PAINT AQUA (-4050 825);
FORCEPROP 1 LASTPIN (-3900 775) $PN 2
J 0
(-3938 787);
DISPLAY 0.617021 (-3938 787);
PAINT ORANGE (-3938 787);
FORCEPROP 1 LAST PART_NUMBER G21796-026
J 0
(-3875 800);
DISPLAY 0.617021 (-3875 800);
PAINT BLUE (-3875 800);
FORCEPROP 1 LAST WATTAGE 1/16W
J 2
(-3525 700);
DISPLAY 0.617021 (-3525 700);
PAINT SKYBLUE (-3525 700);
FORCEPROP 1 LAST MATERIAL CHIP
J 0
(-4000 625);
DISPLAY 0.978723 (-4000 625);
PAINT SKYBLUE (-4000 625);
DISPLAY INVISIBLE (-4000 625);
FORCEPROP 2 LAST CDS_LIB mstr_discrete
J 0
(-4000 775);
PAINT ORANGE (-4000 775);
DISPLAY INVISIBLE (-4000 775);
FORCEPROP 0 LAST ROOM CPU0
J 0
(-4050 925);
DISPLAY 1.021277 (-4050 925);
PAINT ORANGE (-4050 925);
DISPLAY INVISIBLE (-4050 925);
FORCEPROP 1 LAST PATH I303
J 0
(-4050 925);
DISPLAY 0.978723 (-4050 925);
PAINT WHITE (-4050 925);
DISPLAY INVISIBLE (-4050 925);
FORCEPROP 2 LAST SEC 1
J 0
(-4050 975);
DISPLAY 0.680851 (-4050 975);
PAINT MONO (-4050 975);
DISPLAY INVISIBLE (-4050 975);
FORCEPROP 2 LAST SEC_TYPE 0402
J 0
(-4050 975);
DISPLAY 1.021277 (-4050 975);
PAINT ORANGE (-4050 975);
DISPLAY INVISIBLE (-4050 975);
FORCEPROP 1 LAST PACK_TYPE 0402
J 0
(-3750 625);
DISPLAY 0.978723 (-3750 625);
PAINT SKYBLUE (-3750 625);
DISPLAY INVISIBLE (-3750 625);
FORCEADD RES..1
(-4000 575);
FORCEPROP 1 LAST VALUE 1.00K
J 2
(-4050 500);
DISPLAY 0.617021 (-4050 500);
PAINT SKYBLUE (-4050 500);
FORCEPROP 1 LAST TOLERANCE 1%
J 0
(-3925 500);
DISPLAY 0.617021 (-3925 500);
PAINT SKYBLUE (-3925 500);
FORCEPROP 1 LASTPIN (-4100 575) $PN 1
J 0
(-4088 587);
DISPLAY 0.617021 (-4088 587);
PAINT ORANGE (-4088 587);
FORCEPROP 1 LAST LOCATION R6N15
J 0
(-4050 625);
DISPLAY 0.617021 (-4050 625);
PAINT AQUA (-4050 625);
FORCEPROP 1 LASTPIN (-3900 575) $PN 2
J 0
(-3938 587);
DISPLAY 0.617021 (-3938 587);
PAINT ORANGE (-3938 587);
FORCEPROP 1 LAST PART_NUMBER G21796-026
J 0
(-3875 600);
DISPLAY 0.617021 (-3875 600);
PAINT BLUE (-3875 600);
FORCEPROP 1 LAST WATTAGE 1/16W
J 2
(-3525 500);
DISPLAY 0.617021 (-3525 500);
PAINT SKYBLUE (-3525 500);
FORCEPROP 1 LAST MATERIAL CHIP
J 0
(-4000 425);
DISPLAY 0.978723 (-4000 425);
PAINT SKYBLUE (-4000 425);
DISPLAY INVISIBLE (-4000 425);
FORCEPROP 1 LAST PACK_TYPE 0402
J 0
(-3750 425);
DISPLAY 0.978723 (-3750 425);
PAINT SKYBLUE (-3750 425);
DISPLAY INVISIBLE (-3750 425);
FORCEPROP 0 LAST ROOM CPU0
J 0
(-4050 725);
DISPLAY 1.021277 (-4050 725);
PAINT ORANGE (-4050 725);
DISPLAY INVISIBLE (-4050 725);
FORCEPROP 1 LAST PATH I304
J 0
(-4050 725);
DISPLAY 0.978723 (-4050 725);
PAINT WHITE (-4050 725);
DISPLAY INVISIBLE (-4050 725);
FORCEPROP 2 LAST CDS_LIB mstr_discrete
J 0
(-4000 575);
PAINT ORANGE (-4000 575);
DISPLAY INVISIBLE (-4000 575);
FORCEPROP 2 LAST SEC_TYPE 0402
J 0
(-4050 775);
DISPLAY 1.021277 (-4050 775);
PAINT ORANGE (-4050 775);
DISPLAY INVISIBLE (-4050 775);
FORCEPROP 2 LAST SEC 1
J 0
(-4050 775);
DISPLAY 0.680851 (-4050 775);
PAINT MONO (-4050 775);
DISPLAY INVISIBLE (-4050 775);
FORCEADD OFFPAGE..2
(-6550 1525);
FORCEPROP 2 LAST $XR0 21 
J 0
(-6361 1525);
DISPLAY 0.638298 (-6361 1525);
PAINT MONO (-6361 1525);
FORCEPROP 2 LAST CDS_LIB mstr_standard
J 0
(-6550 1525);
PAINT ORANGE (-6550 1525);
DISPLAY INVISIBLE (-6550 1525);
FORCEPROP 2 LAST PATH I305
J 0
(-6500 1600);
DISPLAY 1.021277 (-6500 1600);
PAINT ORANGE (-6500 1600);
DISPLAY INVISIBLE (-6500 1600);
FORCEPROP 1 LAST OFFPAGE TRUE
J 0
(-6225 1400);
DISPLAY 0.872340 (-6225 1400);
PAINT GREEN (-6225 1400);
DISPLAY INVISIBLE (-6225 1400);
FORCEPROP 1 LAST COMMENT_BODY TRUE
J 0
(-6595 1430);
DISPLAY 0.872340 (-6595 1430);
PAINT GREEN (-6595 1430);
DISPLAY INVISIBLE (-6595 1430);
FORCEADD GND..1
(-4275 425);
FORCEPROP 3 LASTPIN (-4275 475) SIG_NAME GND\g
J 0
(-4265 485);
DISPLAY 0.659574 (-4265 485);
PAINT MONO (-4265 485);
DISPLAY INVISIBLE (-4265 485);
FORCEPROP 2 LAST CDS_LIB mstr_symbols
J 0
(-4275 425);
PAINT ORANGE (-4275 425);
DISPLAY INVISIBLE (-4275 425);
FORCEPROP 1 LAST SIZE 1B
J 0
(-4200 375);
DISPLAY 0.872340 (-4200 375);
PAINT AQUA (-4200 375);
DISPLAY INVISIBLE (-4200 375);
FORCEPROP 1 LAST PATH I306
J 0
(-4200 425);
DISPLAY 0.872340 (-4200 425);
PAINT AQUA (-4200 425);
DISPLAY INVISIBLE (-4200 425);
FORCEPROP 1 LAST VOLTAGE 0.0V
J 0
(-4320 382);
DISPLAY 0.340426 (-4320 382);
PAINT SKYBLUE (-4320 382);
DISPLAY INVISIBLE (-4320 382);
FORCEPROP 1 LAST BODY_TYPE PLUMBING
J 0
(-4320 382);
DISPLAY 0.340426 (-4320 382);
PAINT GREEN (-4320 382);
DISPLAY INVISIBLE (-4320 382);
FORCEPROP 1 LAST HDL_POWER GND
J 0
(-4275 575);
DISPLAY 0.872340 (-4275 575);
PAINT GREEN (-4275 575);
DISPLAY INVISIBLE (-4275 575);
FORCEADD OFFPAGE..2
(-2950 975);
FORCEPROP 2 LAST $XR0 21 
J 0
(-2761 975);
DISPLAY 0.638298 (-2761 975);
PAINT MONO (-2761 975);
FORCEPROP 2 LAST CDS_LIB mstr_standard
J 0
(-2950 975);
PAINT ORANGE (-2950 975);
DISPLAY INVISIBLE (-2950 975);
FORCEPROP 2 LAST PATH I308
J 0
(-2775 1050);
DISPLAY 1.021277 (-2775 1050);
PAINT ORANGE (-2775 1050);
DISPLAY INVISIBLE (-2775 1050);
FORCEPROP 1 LAST OFFPAGE TRUE
J 0
(-2625 850);
DISPLAY 0.872340 (-2625 850);
PAINT GREEN (-2625 850);
DISPLAY INVISIBLE (-2625 850);
FORCEPROP 1 LAST COMMENT_BODY TRUE
J 0
(-2995 880);
DISPLAY 0.872340 (-2995 880);
PAINT GREEN (-2995 880);
DISPLAY INVISIBLE (-2995 880);
FORCEADD OFFPAGE..2
(-2950 775);
FORCEPROP 2 LAST $XR0 21 
J 0
(-2761 775);
DISPLAY 0.638298 (-2761 775);
PAINT MONO (-2761 775);
FORCEPROP 2 LAST CDS_LIB mstr_standard
J 0
(-2950 775);
PAINT ORANGE (-2950 775);
DISPLAY INVISIBLE (-2950 775);
FORCEPROP 2 LAST PATH I309
J 0
(-2775 850);
DISPLAY 1.021277 (-2775 850);
PAINT ORANGE (-2775 850);
DISPLAY INVISIBLE (-2775 850);
FORCEPROP 1 LAST OFFPAGE TRUE
J 0
(-2625 650);
DISPLAY 0.872340 (-2625 650);
PAINT GREEN (-2625 650);
DISPLAY INVISIBLE (-2625 650);
FORCEPROP 1 LAST COMMENT_BODY TRUE
J 0
(-2995 680);
DISPLAY 0.872340 (-2995 680);
PAINT GREEN (-2995 680);
DISPLAY INVISIBLE (-2995 680);
FORCEADD OFFPAGE..2
(-2950 575);
FORCEPROP 2 LAST $XR0 21 
J 0
(-2761 575);
DISPLAY 0.638298 (-2761 575);
PAINT MONO (-2761 575);
FORCEPROP 2 LAST CDS_LIB mstr_standard
J 0
(-2950 575);
PAINT ORANGE (-2950 575);
DISPLAY INVISIBLE (-2950 575);
FORCEPROP 2 LAST PATH I310
J 0
(-2775 650);
DISPLAY 1.021277 (-2775 650);
PAINT ORANGE (-2775 650);
DISPLAY INVISIBLE (-2775 650);
FORCEPROP 1 LAST OFFPAGE TRUE
J 0
(-2625 450);
DISPLAY 0.872340 (-2625 450);
PAINT GREEN (-2625 450);
DISPLAY INVISIBLE (-2625 450);
FORCEPROP 1 LAST COMMENT_BODY TRUE
J 0
(-2995 480);
DISPLAY 0.872340 (-2995 480);
PAINT GREEN (-2995 480);
DISPLAY INVISIBLE (-2995 480);
FORCEADD GND..1
(-2175 425);
FORCEPROP 3 LASTPIN (-2175 475) SIG_NAME GND\g
J 0
(-2165 485);
DISPLAY 0.659574 (-2165 485);
PAINT MONO (-2165 485);
DISPLAY INVISIBLE (-2165 485);
FORCEPROP 2 LAST CDS_LIB mstr_symbols
J 0
(-2175 425);
PAINT ORANGE (-2175 425);
DISPLAY INVISIBLE (-2175 425);
FORCEPROP 1 LAST SIZE 1B
J 0
(-2100 375);
DISPLAY 0.872340 (-2100 375);
PAINT AQUA (-2100 375);
DISPLAY INVISIBLE (-2100 375);
FORCEPROP 1 LAST VOLTAGE 0.0V
J 0
(-2220 382);
DISPLAY 0.340426 (-2220 382);
PAINT SKYBLUE (-2220 382);
DISPLAY INVISIBLE (-2220 382);
FORCEPROP 1 LAST PATH I311
J 0
(-2100 425);
DISPLAY 0.872340 (-2100 425);
PAINT AQUA (-2100 425);
DISPLAY INVISIBLE (-2100 425);
FORCEPROP 1 LAST BODY_TYPE PLUMBING
J 0
(-2220 382);
DISPLAY 0.340426 (-2220 382);
PAINT GREEN (-2220 382);
DISPLAY INVISIBLE (-2220 382);
FORCEPROP 1 LAST HDL_POWER GND
J 0
(-2175 575);
DISPLAY 0.872340 (-2175 575);
PAINT GREEN (-2175 575);
DISPLAY INVISIBLE (-2175 575);
FORCEADD RES..1
(-1900 575);
FORCEPROP 1 LAST VALUE 1.00K
J 2
(-1950 500);
DISPLAY 0.617021 (-1950 500);
PAINT SKYBLUE (-1950 500);
FORCEPROP 1 LAST TOLERANCE 1%
J 0
(-1825 500);
DISPLAY 0.617021 (-1825 500);
PAINT SKYBLUE (-1825 500);
FORCEPROP 1 LASTPIN (-2000 575) $PN 1
J 0
(-1988 587);
DISPLAY 0.617021 (-1988 587);
PAINT ORANGE (-1988 587);
FORCEPROP 1 LAST LOCATION R1C32
J 0
(-1950 625);
DISPLAY 0.617021 (-1950 625);
PAINT AQUA (-1950 625);
FORCEPROP 1 LASTPIN (-1800 575) $PN 2
J 0
(-1838 587);
DISPLAY 0.617021 (-1838 587);
PAINT ORANGE (-1838 587);
FORCEPROP 1 LAST WATTAGE 1/16W
J 2
(-1425 500);
DISPLAY 0.617021 (-1425 500);
PAINT SKYBLUE (-1425 500);
FORCEPROP 1 LAST PART_NUMBER G21796-026
J 0
(-1775 600);
DISPLAY 0.617021 (-1775 600);
PAINT BLUE (-1775 600);
FORCEPROP 1 LAST MATERIAL CHIP
J 0
(-1900 425);
DISPLAY 0.978723 (-1900 425);
PAINT SKYBLUE (-1900 425);
DISPLAY INVISIBLE (-1900 425);
FORCEPROP 1 LAST PACK_TYPE 0402
J 0
(-1650 425);
DISPLAY 0.978723 (-1650 425);
PAINT SKYBLUE (-1650 425);
DISPLAY INVISIBLE (-1650 425);
FORCEPROP 0 LAST ROOM CPU1
J 0
(-1950 725);
DISPLAY 1.021277 (-1950 725);
PAINT ORANGE (-1950 725);
DISPLAY INVISIBLE (-1950 725);
FORCEPROP 1 LAST PATH I312
J 0
(-1950 725);
DISPLAY 0.978723 (-1950 725);
PAINT WHITE (-1950 725);
DISPLAY INVISIBLE (-1950 725);
FORCEPROP 2 LAST CDS_LIB mstr_discrete
J 0
(-1900 575);
PAINT ORANGE (-1900 575);
DISPLAY INVISIBLE (-1900 575);
FORCEPROP 2 LAST SEC 1
J 0
(-1950 775);
DISPLAY 0.680851 (-1950 775);
PAINT MONO (-1950 775);
DISPLAY INVISIBLE (-1950 775);
FORCEPROP 2 LAST SEC_TYPE 0402
J 0
(-1950 775);
DISPLAY 1.021277 (-1950 775);
PAINT ORANGE (-1950 775);
DISPLAY INVISIBLE (-1950 775);
FORCEADD RES..1
(-1900 775);
FORCEPROP 1 LAST VALUE 1.00K
J 2
(-1950 700);
DISPLAY 0.617021 (-1950 700);
PAINT SKYBLUE (-1950 700);
FORCEPROP 1 LASTPIN (-2000 775) $PN 1
J 0
(-1988 787);
DISPLAY 0.617021 (-1988 787);
PAINT ORANGE (-1988 787);
FORCEPROP 1 LAST LOCATION R1C33
J 0
(-1950 825);
DISPLAY 0.617021 (-1950 825);
PAINT AQUA (-1950 825);
FORCEPROP 1 LASTPIN (-1800 775) $PN 2
J 0
(-1838 787);
DISPLAY 0.617021 (-1838 787);
PAINT ORANGE (-1838 787);
FORCEPROP 1 LAST TOLERANCE 1%
J 0
(-1825 700);
DISPLAY 0.617021 (-1825 700);
PAINT SKYBLUE (-1825 700);
FORCEPROP 1 LAST WATTAGE 1/16W
J 2
(-1425 700);
DISPLAY 0.617021 (-1425 700);
PAINT SKYBLUE (-1425 700);
FORCEPROP 1 LAST PART_NUMBER G21796-026
J 0
(-1775 800);
DISPLAY 0.617021 (-1775 800);
PAINT BLUE (-1775 800);
FORCEPROP 1 LAST MATERIAL CHIP
J 0
(-1900 625);
DISPLAY 0.978723 (-1900 625);
PAINT SKYBLUE (-1900 625);
DISPLAY INVISIBLE (-1900 625);
FORCEPROP 0 LAST ROOM CPU1
J 0
(-1950 925);
DISPLAY 1.021277 (-1950 925);
PAINT ORANGE (-1950 925);
DISPLAY INVISIBLE (-1950 925);
FORCEPROP 1 LAST PATH I313
J 0
(-1950 925);
DISPLAY 0.978723 (-1950 925);
PAINT WHITE (-1950 925);
DISPLAY INVISIBLE (-1950 925);
FORCEPROP 2 LAST SEC 1
J 0
(-1950 975);
DISPLAY 0.680851 (-1950 975);
PAINT MONO (-1950 975);
DISPLAY INVISIBLE (-1950 975);
FORCEPROP 2 LAST SEC_TYPE 0402
J 0
(-1950 975);
DISPLAY 1.021277 (-1950 975);
PAINT ORANGE (-1950 975);
DISPLAY INVISIBLE (-1950 975);
FORCEPROP 2 LAST CDS_LIB mstr_discrete
J 0
(-1900 775);
PAINT ORANGE (-1900 775);
DISPLAY INVISIBLE (-1900 775);
FORCEPROP 1 LAST PACK_TYPE 0402
J 0
(-1650 625);
DISPLAY 0.978723 (-1650 625);
PAINT SKYBLUE (-1650 625);
DISPLAY INVISIBLE (-1650 625);
FORCEADD OFFPAGE..2
(-850 575);
FORCEPROP 2 LAST $XR0 55 
J 0
(-661 575);
DISPLAY 0.638298 (-661 575);
PAINT MONO (-661 575);
FORCEPROP 2 LAST CDS_LIB mstr_standard
J 0
(-850 575);
PAINT ORANGE (-850 575);
DISPLAY INVISIBLE (-850 575);
FORCEPROP 2 LAST PATH I314
J 0
(-675 650);
DISPLAY 1.021277 (-675 650);
PAINT ORANGE (-675 650);
DISPLAY INVISIBLE (-675 650);
FORCEPROP 1 LAST OFFPAGE TRUE
J 0
(-525 450);
DISPLAY 0.872340 (-525 450);
PAINT GREEN (-525 450);
DISPLAY INVISIBLE (-525 450);
FORCEPROP 1 LAST COMMENT_BODY TRUE
J 0
(-895 480);
DISPLAY 0.872340 (-895 480);
PAINT GREEN (-895 480);
DISPLAY INVISIBLE (-895 480);
FORCEADD OFFPAGE..2
(-850 775);
FORCEPROP 2 LAST $XR0 55 
J 0
(-661 775);
DISPLAY 0.638298 (-661 775);
PAINT MONO (-661 775);
FORCEPROP 2 LAST CDS_LIB mstr_standard
J 0
(-850 775);
PAINT ORANGE (-850 775);
DISPLAY INVISIBLE (-850 775);
FORCEPROP 2 LAST PATH I315
J 0
(-675 850);
DISPLAY 1.021277 (-675 850);
PAINT ORANGE (-675 850);
DISPLAY INVISIBLE (-675 850);
FORCEPROP 1 LAST OFFPAGE TRUE
J 0
(-525 650);
DISPLAY 0.872340 (-525 650);
PAINT GREEN (-525 650);
DISPLAY INVISIBLE (-525 650);
FORCEPROP 1 LAST COMMENT_BODY TRUE
J 0
(-895 680);
DISPLAY 0.872340 (-895 680);
PAINT GREEN (-895 680);
DISPLAY INVISIBLE (-895 680);
FORCEADD OFFPAGE..2
(-850 975);
FORCEPROP 2 LAST $XR0 55 
J 0
(-661 975);
DISPLAY 0.638298 (-661 975);
PAINT MONO (-661 975);
FORCEPROP 2 LAST CDS_LIB mstr_standard
J 0
(-850 975);
PAINT ORANGE (-850 975);
DISPLAY INVISIBLE (-850 975);
FORCEPROP 2 LAST PATH I316
J 0
(-675 1050);
DISPLAY 1.021277 (-675 1050);
PAINT ORANGE (-675 1050);
DISPLAY INVISIBLE (-675 1050);
FORCEPROP 1 LAST OFFPAGE TRUE
J 0
(-525 850);
DISPLAY 0.872340 (-525 850);
PAINT GREEN (-525 850);
DISPLAY INVISIBLE (-525 850);
FORCEPROP 1 LAST COMMENT_BODY TRUE
J 0
(-895 880);
DISPLAY 0.872340 (-895 880);
PAINT GREEN (-895 880);
DISPLAY INVISIBLE (-895 880);
FORCEADD P3V3_STBY..1
(-2175 1100);
FORCEPROP 3 LASTPIN (-2175 1050) SIG_NAME P3V3_STBY\g
J 0
(-2165 1060);
DISPLAY 0.659574 (-2165 1060);
PAINT MONO (-2165 1060);
DISPLAY INVISIBLE (-2165 1060);
FORCEPROP 1 LAST SIZE 1B
J 0
(-2130 1122);
DISPLAY 0.340426 (-2130 1122);
PAINT GREEN (-2130 1122);
DISPLAY INVISIBLE (-2130 1122);
FORCEPROP 2 LAST CDS_LIB mstr_symbols
J 0
(-2175 1100);
PAINT ORANGE (-2175 1100);
DISPLAY INVISIBLE (-2175 1100);
FORCEPROP 1 LAST PATH I318
J 0
(-2130 1102);
DISPLAY 0.340426 (-2130 1102);
PAINT GREEN (-2130 1102);
DISPLAY INVISIBLE (-2130 1102);
FORCEPROP 1 LAST VOLTAGE 3.3V
J 0
(-2220 1057);
DISPLAY 0.340426 (-2220 1057);
PAINT SKYBLUE (-2220 1057);
DISPLAY INVISIBLE (-2220 1057);
FORCEPROP 1 LAST BODY_TYPE PLUMBING
J 0
(-2220 1057);
DISPLAY 0.340426 (-2220 1057);
PAINT GREEN (-2220 1057);
DISPLAY INVISIBLE (-2220 1057);
FORCEPROP 1 LAST HDL_POWER P3V3_STBY
J 0
(-2475 975);
DISPLAY 0.872340 (-2475 975);
PAINT ORANGE (-2475 975);
DISPLAY INVISIBLE (-2475 975);
FORCEADD RES..1
(-1900 975);
FORCEPROP 1 LAST VALUE 10.0K
J 2
(-1950 900);
DISPLAY 0.617021 (-1950 900);
PAINT SKYBLUE (-1950 900);
FORCEPROP 1 LASTPIN (-2000 975) $PN 1
J 0
(-1988 987);
DISPLAY 0.617021 (-1988 987);
PAINT ORANGE (-1988 987);
FORCEPROP 1 LASTPIN (-1800 975) $PN 2
J 0
(-1838 987);
DISPLAY 0.617021 (-1838 987);
PAINT ORANGE (-1838 987);
FORCEPROP 1 LAST TOLERANCE 1%
J 0
(-1825 900);
DISPLAY 0.617021 (-1825 900);
PAINT SKYBLUE (-1825 900);
FORCEPROP 1 LAST WATTAGE 1/16W
J 2
(-1425 900);
DISPLAY 0.617021 (-1425 900);
PAINT SKYBLUE (-1425 900);
FORCEPROP 1 LAST PART_NUMBER G21796-016
J 0
(-1775 1000);
DISPLAY 0.617021 (-1775 1000);
PAINT BLUE (-1775 1000);
FORCEPROP 1 LAST LOCATION R1C34
J 0
(-1950 1025);
DISPLAY 0.617021 (-1950 1025);
PAINT AQUA (-1950 1025);
FORCEPROP 1 LAST MATERIAL CHIP
J 0
(-1900 825);
DISPLAY 0.978723 (-1900 825);
PAINT SKYBLUE (-1900 825);
DISPLAY INVISIBLE (-1900 825);
FORCEPROP 2 LAST CDS_LIB mstr_discrete
J 0
(-1900 975);
PAINT ORANGE (-1900 975);
DISPLAY INVISIBLE (-1900 975);
FORCEPROP 1 LAST PACK_TYPE 0402
J 0
(-1650 825);
DISPLAY 0.978723 (-1650 825);
PAINT SKYBLUE (-1650 825);
DISPLAY INVISIBLE (-1650 825);
FORCEPROP 2 LAST SEC_TYPE 0402
J 0
(-1950 1175);
DISPLAY 1.021277 (-1950 1175);
PAINT ORANGE (-1950 1175);
DISPLAY INVISIBLE (-1950 1175);
FORCEPROP 2 LAST SEC 1
J 0
(-1950 1175);
DISPLAY 0.680851 (-1950 1175);
PAINT MONO (-1950 1175);
DISPLAY INVISIBLE (-1950 1175);
FORCEPROP 1 LAST PATH I320
J 0
(-1950 1125);
DISPLAY 0.978723 (-1950 1125);
PAINT WHITE (-1950 1125);
DISPLAY INVISIBLE (-1950 1125);
FORCEPROP 0 LAST ROOM CPU1
J 0
(-1950 1125);
DISPLAY 1.021277 (-1950 1125);
PAINT ORANGE (-1950 1125);
DISPLAY INVISIBLE (-1950 1125);
FORCEADD RES..1
(-6425 850);
FORCEPROP 1 LAST VALUE 0.0
J 2
(-6475 775);
DISPLAY 0.617021 (-6475 775);
PAINT SKYBLUE (-6475 775);
FORCEPROP 1 LASTPIN (-6525 850) $PN 1
J 0
(-6513 862);
DISPLAY 0.617021 (-6513 862);
PAINT ORANGE (-6513 862);
FORCEPROP 1 LAST LOCATION R9M21
J 0
(-6475 900);
DISPLAY 0.617021 (-6475 900);
PAINT AQUA (-6475 900);
FORCEPROP 1 LASTPIN (-6325 850) $PN 2
J 0
(-6363 862);
DISPLAY 0.617021 (-6363 862);
PAINT ORANGE (-6363 862);
FORCEPROP 1 LAST PACK_TYPE 0402
J 0
(-6325 775);
DISPLAY 0.617021 (-6325 775);
PAINT SKYBLUE (-6325 775);
FORCEPROP 1 LAST PART_NUMBER G21497-005
J 0
(-6325 875);
DISPLAY 0.617021 (-6325 875);
PAINT BLUE (-6325 875);
FORCEPROP 1 LAST WATTAGE 1/16W
J 2
(-6450 700);
DISPLAY 0.978723 (-6450 700);
PAINT SKYBLUE (-6450 700);
DISPLAY INVISIBLE (-6450 700);
FORCEPROP 1 LAST MATERIAL CHIP
J 0
(-6425 700);
DISPLAY 0.978723 (-6425 700);
PAINT SKYBLUE (-6425 700);
DISPLAY INVISIBLE (-6425 700);
FORCEPROP 1 LAST TOLERANCE 5%
J 0
(-6425 750);
DISPLAY 0.978723 (-6425 750);
PAINT SKYBLUE (-6425 750);
DISPLAY INVISIBLE (-6425 750);
FORCEPROP 2 LAST CDS_LIB mstr_discrete
J 0
(-6425 850);
PAINT ORANGE (-6425 850);
DISPLAY INVISIBLE (-6425 850);
FORCEPROP 0 LAST ROOM CPU1
J 0
(-6325 975);
DISPLAY 1.021277 (-6325 975);
PAINT ORANGE (-6325 975);
DISPLAY INVISIBLE (-6325 975);
FORCEPROP 1 LAST PATH I321
J 0
(-6475 1000);
DISPLAY 0.978723 (-6475 1000);
PAINT WHITE (-6475 1000);
DISPLAY INVISIBLE (-6475 1000);
FORCEPROP 2 LAST SEC_TYPE 0402
J 0
(-6475 1050);
DISPLAY 1.021277 (-6475 1050);
PAINT ORANGE (-6475 1050);
DISPLAY INVISIBLE (-6475 1050);
FORCEPROP 2 LAST SEC 1
J 0
(-6475 1050);
DISPLAY 0.680851 (-6475 1050);
PAINT MONO (-6475 1050);
DISPLAY INVISIBLE (-6475 1050);
FORCEADD RES..1
(-6425 700);
FORCEPROP 1 LASTPIN (-6525 700) $PN 1
J 0
(-6513 712);
DISPLAY 0.617021 (-6513 712);
PAINT ORANGE (-6513 712);
FORCEPROP 1 LAST LOCATION R4A8
J 0
(-6475 750);
DISPLAY 0.617021 (-6475 750);
PAINT AQUA (-6475 750);
FORCEPROP 1 LAST PACK_TYPE 0402
J 0
(-6325 625);
DISPLAY 0.617021 (-6325 625);
PAINT SKYBLUE (-6325 625);
FORCEPROP 1 LASTPIN (-6325 700) $PN 2
J 0
(-6363 712);
DISPLAY 0.617021 (-6363 712);
PAINT ORANGE (-6363 712);
FORCEPROP 1 LAST PART_NUMBER G21497-005
J 0
(-6325 725);
DISPLAY 0.617021 (-6325 725);
PAINT BLUE (-6325 725);
FORCEPROP 1 LAST VALUE 0.0
J 2
(-6475 625);
DISPLAY 0.617021 (-6475 625);
PAINT SKYBLUE (-6475 625);
FORCEPROP 1 LAST WATTAGE 1/16W
J 2
(-6450 550);
DISPLAY 0.978723 (-6450 550);
PAINT SKYBLUE (-6450 550);
DISPLAY INVISIBLE (-6450 550);
FORCEPROP 1 LAST MATERIAL CHIP
J 0
(-6425 550);
DISPLAY 0.978723 (-6425 550);
PAINT SKYBLUE (-6425 550);
DISPLAY INVISIBLE (-6425 550);
FORCEPROP 1 LAST TOLERANCE 5%
J 0
(-6425 600);
DISPLAY 0.978723 (-6425 600);
PAINT SKYBLUE (-6425 600);
DISPLAY INVISIBLE (-6425 600);
FORCEPROP 2 LAST CDS_LIB mstr_discrete
J 0
(-6425 700);
PAINT ORANGE (-6425 700);
DISPLAY INVISIBLE (-6425 700);
FORCEPROP 1 LAST PATH I322
J 0
(-6475 850);
DISPLAY 0.978723 (-6475 850);
PAINT WHITE (-6475 850);
DISPLAY INVISIBLE (-6475 850);
FORCEPROP 2 LAST SEC_TYPE 0402
J 0
(-6475 900);
DISPLAY 1.021277 (-6475 900);
PAINT ORANGE (-6475 900);
DISPLAY INVISIBLE (-6475 900);
FORCEPROP 2 LAST SEC 1
J 0
(-6475 900);
DISPLAY 0.680851 (-6475 900);
PAINT MONO (-6475 900);
DISPLAY INVISIBLE (-6475 900);
FORCEPROP 0 LAST ROOM CPU0
J 0
(-6325 825);
DISPLAY 1.021277 (-6325 825);
PAINT ORANGE (-6325 825);
DISPLAY INVISIBLE (-6325 825);
FORCEADD RES..1
(-6425 550);
FORCEPROP 1 LAST VALUE 0.0
J 2
(-6475 475);
DISPLAY 0.617021 (-6475 475);
PAINT SKYBLUE (-6475 475);
FORCEPROP 1 LASTPIN (-6525 550) $PN 1
J 0
(-6513 562);
DISPLAY 0.617021 (-6513 562);
PAINT ORANGE (-6513 562);
FORCEPROP 1 LAST PART_NUMBER G21497-005
J 0
(-6325 575);
DISPLAY 0.617021 (-6325 575);
PAINT BLUE (-6325 575);
FORCEPROP 1 LASTPIN (-6325 550) $PN 2
J 0
(-6363 562);
DISPLAY 0.617021 (-6363 562);
PAINT ORANGE (-6363 562);
FORCEPROP 1 LAST LOCATION R9M20
J 0
(-6475 600);
DISPLAY 0.617021 (-6475 600);
PAINT AQUA (-6475 600);
FORCEPROP 1 LAST PACK_TYPE 0402
J 0
(-6325 475);
DISPLAY 0.617021 (-6325 475);
PAINT SKYBLUE (-6325 475);
FORCEPROP 1 LAST WATTAGE 1/16W
J 2
(-6450 400);
DISPLAY 0.978723 (-6450 400);
PAINT SKYBLUE (-6450 400);
DISPLAY INVISIBLE (-6450 400);
FORCEPROP 1 LAST MATERIAL CHIP
J 0
(-6425 400);
DISPLAY 0.978723 (-6425 400);
PAINT SKYBLUE (-6425 400);
DISPLAY INVISIBLE (-6425 400);
FORCEPROP 1 LAST TOLERANCE 5%
J 0
(-6425 450);
DISPLAY 0.978723 (-6425 450);
PAINT SKYBLUE (-6425 450);
DISPLAY INVISIBLE (-6425 450);
FORCEPROP 2 LAST CDS_LIB mstr_discrete
J 0
(-6425 550);
PAINT ORANGE (-6425 550);
DISPLAY INVISIBLE (-6425 550);
FORCEPROP 1 LAST PATH I323
J 0
(-6475 700);
DISPLAY 0.978723 (-6475 700);
PAINT WHITE (-6475 700);
DISPLAY INVISIBLE (-6475 700);
FORCEPROP 2 LAST SEC_TYPE 0402
J 0
(-6475 750);
DISPLAY 1.021277 (-6475 750);
PAINT ORANGE (-6475 750);
DISPLAY INVISIBLE (-6475 750);
FORCEPROP 2 LAST SEC 1
J 0
(-6475 750);
DISPLAY 0.680851 (-6475 750);
PAINT MONO (-6475 750);
DISPLAY INVISIBLE (-6475 750);
FORCEPROP 0 LAST ROOM CPU1
J 0
(-6325 675);
DISPLAY 1.021277 (-6325 675);
PAINT ORANGE (-6325 675);
DISPLAY INVISIBLE (-6325 675);
FORCEADD RES..1
(-6425 400);
FORCEPROP 1 LASTPIN (-6525 400) $PN 1
J 0
(-6513 412);
DISPLAY 0.617021 (-6513 412);
PAINT ORANGE (-6513 412);
FORCEPROP 1 LAST LOCATION R4A9
J 0
(-6475 450);
DISPLAY 0.617021 (-6475 450);
PAINT AQUA (-6475 450);
FORCEPROP 1 LASTPIN (-6325 400) $PN 2
J 0
(-6363 412);
DISPLAY 0.617021 (-6363 412);
PAINT ORANGE (-6363 412);
FORCEPROP 1 LAST VALUE 0.0
J 2
(-6475 325);
DISPLAY 0.617021 (-6475 325);
PAINT SKYBLUE (-6475 325);
FORCEPROP 1 LAST PACK_TYPE 0402
J 0
(-6325 325);
DISPLAY 0.617021 (-6325 325);
PAINT SKYBLUE (-6325 325);
FORCEPROP 1 LAST PART_NUMBER G21497-005
J 0
(-6325 425);
DISPLAY 0.617021 (-6325 425);
PAINT BLUE (-6325 425);
FORCEPROP 1 LAST WATTAGE 1/16W
J 2
(-6450 250);
DISPLAY 0.978723 (-6450 250);
PAINT SKYBLUE (-6450 250);
DISPLAY INVISIBLE (-6450 250);
FORCEPROP 1 LAST MATERIAL CHIP
J 0
(-6425 250);
DISPLAY 0.978723 (-6425 250);
PAINT SKYBLUE (-6425 250);
DISPLAY INVISIBLE (-6425 250);
FORCEPROP 1 LAST TOLERANCE 5%
J 0
(-6425 300);
DISPLAY 0.978723 (-6425 300);
PAINT SKYBLUE (-6425 300);
DISPLAY INVISIBLE (-6425 300);
FORCEPROP 2 LAST CDS_LIB mstr_discrete
J 0
(-6425 400);
PAINT ORANGE (-6425 400);
DISPLAY INVISIBLE (-6425 400);
FORCEPROP 2 LAST SEC 1
J 0
(-6475 600);
DISPLAY 0.680851 (-6475 600);
PAINT MONO (-6475 600);
DISPLAY INVISIBLE (-6475 600);
FORCEPROP 1 LAST PATH I324
J 0
(-6475 550);
DISPLAY 0.978723 (-6475 550);
PAINT WHITE (-6475 550);
DISPLAY INVISIBLE (-6475 550);
FORCEPROP 2 LAST SEC_TYPE 0402
J 0
(-6475 600);
DISPLAY 1.021277 (-6475 600);
PAINT ORANGE (-6475 600);
DISPLAY INVISIBLE (-6475 600);
FORCEPROP 0 LAST ROOM CPU0
J 0
(-6325 525);
DISPLAY 1.021277 (-6325 525);
PAINT ORANGE (-6325 525);
DISPLAY INVISIBLE (-6325 525);
FORCEADD OFFPAGE..6
(-7350 700);
FORCEPROP 2 LAST $XR0 138 
J 0
(-7660 700);
DISPLAY 0.638298 (-7660 700);
PAINT MONO (-7660 700);
FORCEPROP 2 LAST $XR1 160 
J 0
(-7780 700);
DISPLAY 0.638298 (-7780 700);
PAINT MONO (-7780 700);
FORCEPROP 2 LAST $XR2 182 
J 0
(-7900 700);
DISPLAY 0.638298 (-7900 700);
PAINT MONO (-7900 700);
FORCEPROP 2 LAST $XR4 ?
J 0
(-7900 700);
DISPLAY 0.638298 (-7900 700);
PAINT MONO (-7900 700);
FORCEPROP 2 LAST $XR3 ?
J 0
(-7900 700);
DISPLAY 0.638298 (-7900 700);
PAINT MONO (-7900 700);
FORCEPROP 2 LAST PATH I325
J 0
(-7300 775);
DISPLAY 1.021277 (-7300 775);
PAINT ORANGE (-7300 775);
DISPLAY INVISIBLE (-7300 775);
FORCEPROP 2 LAST CDS_LIB mstr_standard
J 0
(-7350 700);
PAINT ORANGE (-7350 700);
DISPLAY INVISIBLE (-7350 700);
FORCEPROP 1 LAST OFFPAGE TRUE
J 0
(-7025 575);
DISPLAY 0.872340 (-7025 575);
PAINT GREEN (-7025 575);
DISPLAY INVISIBLE (-7025 575);
FORCEPROP 1 LAST COMMENT_BODY TRUE
J 0
(-7250 625);
DISPLAY 0.872340 (-7250 625);
PAINT GREEN (-7250 625);
DISPLAY INVISIBLE (-7250 625);
FORCEADD OFFPAGE..1
(-7350 400);
FORCEPROP 2 LAST $XR0 138 
J 0
(-7602 400);
DISPLAY 0.638298 (-7602 400);
PAINT MONO (-7602 400);
FORCEPROP 2 LAST $XR1 160 
J 0
(-7722 400);
DISPLAY 0.638298 (-7722 400);
PAINT MONO (-7722 400);
FORCEPROP 2 LAST $XR2 182 
J 0
(-7842 400);
DISPLAY 0.638298 (-7842 400);
PAINT MONO (-7842 400);
FORCEPROP 2 LAST $XR4 ?
J 0
(-7842 400);
DISPLAY 0.638298 (-7842 400);
PAINT MONO (-7842 400);
FORCEPROP 2 LAST $XR3 ?
J 0
(-7842 400);
DISPLAY 0.638298 (-7842 400);
PAINT MONO (-7842 400);
FORCEPROP 2 LAST CDS_LIB mstr_standard
J 0
(-7350 400);
PAINT ORANGE (-7350 400);
DISPLAY INVISIBLE (-7350 400);
FORCEPROP 2 LAST PATH I326
J 0
(-7300 475);
DISPLAY 1.021277 (-7300 475);
PAINT ORANGE (-7300 475);
DISPLAY INVISIBLE (-7300 475);
FORCEPROP 1 LAST OFFPAGE TRUE
J 0
(-7025 275);
DISPLAY 0.872340 (-7025 275);
PAINT GREEN (-7025 275);
DISPLAY INVISIBLE (-7025 275);
FORCEPROP 1 LAST COMMENT_BODY TRUE
J 0
(-7225 300);
DISPLAY 0.872340 (-7225 300);
PAINT GREEN (-7225 300);
DISPLAY INVISIBLE (-7225 300);
FORCEADD OFFPAGE..3
(-5350 850);
FORCEPROP 2 LAST $XR0 55 
J 0
(-5136 850);
DISPLAY 0.638298 (-5136 850);
PAINT MONO (-5136 850);
FORCEPROP 2 LAST PATH I327
J 0
(-5300 925);
DISPLAY 1.021277 (-5300 925);
PAINT ORANGE (-5300 925);
DISPLAY INVISIBLE (-5300 925);
FORCEPROP 2 LAST CDS_LIB mstr_standard
J 0
(-5350 850);
PAINT ORANGE (-5350 850);
DISPLAY INVISIBLE (-5350 850);
FORCEPROP 1 LAST OFFPAGE TRUE
J 0
(-5025 725);
DISPLAY 0.872340 (-5025 725);
PAINT GREEN (-5025 725);
DISPLAY INVISIBLE (-5025 725);
FORCEPROP 1 LAST COMMENT_BODY TRUE
J 0
(-5400 750);
DISPLAY 0.872340 (-5400 750);
PAINT GREEN (-5400 750);
DISPLAY INVISIBLE (-5400 750);
FORCEADD OFFPAGE..3
(-5350 700);
FORCEPROP 2 LAST $XR0 21 
J 0
(-5136 700);
DISPLAY 0.638298 (-5136 700);
PAINT MONO (-5136 700);
FORCEPROP 2 LAST CDS_LIB mstr_standard
J 0
(-5350 700);
PAINT ORANGE (-5350 700);
DISPLAY INVISIBLE (-5350 700);
FORCEPROP 2 LAST PATH I328
J 0
(-5175 775);
DISPLAY 1.021277 (-5175 775);
PAINT ORANGE (-5175 775);
DISPLAY INVISIBLE (-5175 775);
FORCEPROP 1 LAST OFFPAGE TRUE
J 0
(-5025 575);
DISPLAY 0.872340 (-5025 575);
PAINT GREEN (-5025 575);
DISPLAY INVISIBLE (-5025 575);
FORCEPROP 1 LAST COMMENT_BODY TRUE
J 0
(-5400 600);
DISPLAY 0.872340 (-5400 600);
PAINT GREEN (-5400 600);
DISPLAY INVISIBLE (-5400 600);
FORCEADD OFFPAGE..2
(-5350 550);
FORCEPROP 2 LAST $XR0 55 
J 0
(-5161 550);
DISPLAY 0.638298 (-5161 550);
PAINT MONO (-5161 550);
FORCEPROP 2 LAST CDS_LIB mstr_standard
J 0
(-5350 550);
PAINT ORANGE (-5350 550);
DISPLAY INVISIBLE (-5350 550);
FORCEPROP 2 LAST PATH I329
J 0
(-5175 625);
DISPLAY 1.021277 (-5175 625);
PAINT ORANGE (-5175 625);
DISPLAY INVISIBLE (-5175 625);
FORCEPROP 1 LAST OFFPAGE TRUE
J 0
(-5025 425);
DISPLAY 0.872340 (-5025 425);
PAINT GREEN (-5025 425);
DISPLAY INVISIBLE (-5025 425);
FORCEPROP 1 LAST COMMENT_BODY TRUE
J 0
(-5395 455);
DISPLAY 0.872340 (-5395 455);
PAINT GREEN (-5395 455);
DISPLAY INVISIBLE (-5395 455);
FORCEADD OFFPAGE..2
(-5350 400);
FORCEPROP 2 LAST $XR0 21 
J 0
(-5161 400);
DISPLAY 0.638298 (-5161 400);
PAINT MONO (-5161 400);
FORCEPROP 2 LAST CDS_LIB mstr_standard
J 0
(-5350 400);
PAINT ORANGE (-5350 400);
DISPLAY INVISIBLE (-5350 400);
FORCEPROP 2 LAST PATH I330
J 0
(-5175 475);
DISPLAY 1.021277 (-5175 475);
PAINT ORANGE (-5175 475);
DISPLAY INVISIBLE (-5175 475);
FORCEPROP 1 LAST OFFPAGE TRUE
J 0
(-5025 275);
DISPLAY 0.872340 (-5025 275);
PAINT GREEN (-5025 275);
DISPLAY INVISIBLE (-5025 275);
FORCEPROP 1 LAST COMMENT_BODY TRUE
J 0
(-5395 305);
DISPLAY 0.872340 (-5395 305);
PAINT GREEN (-5395 305);
DISPLAY INVISIBLE (-5395 305);
FORCEADD RES..2
(-7650 1700);
FORCEPROP 1 LAST PACK_TYPE 0402
J 0
(-7610 1525);
DISPLAY 0.617021 (-7610 1525);
PAINT SKYBLUE (-7610 1525);
FORCEPROP 1 LASTPIN (-7650 1600) $PN 2
J 0
(-7645 1610);
DISPLAY 0.617021 (-7645 1610);
PAINT ORANGE (-7645 1610);
FORCEPROP 1 LASTPIN (-7650 1800) $PN 1
J 0
(-7645 1762);
DISPLAY 0.617021 (-7645 1762);
PAINT ORANGE (-7645 1762);
FORCEPROP 1 LAST TOLERANCE 1%
J 0
(-7505 1725);
DISPLAY 0.617021 (-7505 1725);
PAINT SKYBLUE (-7505 1725);
FORCEPROP 1 LAST LOCATION R3P54
J 0
(-7605 1825);
DISPLAY 0.617021 (-7605 1825);
PAINT AQUA (-7605 1825);
FORCEPROP 1 LAST WATTAGE 1/16W
J 0
(-7535 1675);
DISPLAY 0.617021 (-7535 1675);
PAINT SKYBLUE (-7535 1675);
FORCEPROP 1 LAST VALUE 3.32K
J 0
(-7555 1775);
DISPLAY 0.617021 (-7555 1775);
PAINT SKYBLUE (-7555 1775);
FORCEPROP 1 LAST PART_NUMBER G21796-027
J 0
(-7610 1575);
DISPLAY 0.617021 (-7610 1575);
PAINT BLUE (-7610 1575);
FORCEPROP 1 LAST MATERIAL EMPTY
J 0
(-7560 1625);
DISPLAY 0.617021 (-7560 1625);
PAINT RED (-7560 1625);
FORCEPROP 2 LAST CDS_LIB mstr_discrete
J 0
(-7650 1700);
PAINT ORANGE (-7650 1700);
DISPLAY INVISIBLE (-7650 1700);
FORCEPROP 0 LAST ROOM CPU0
J 0
(-7600 1925);
DISPLAY 1.021277 (-7600 1925);
PAINT ORANGE (-7600 1925);
DISPLAY INVISIBLE (-7600 1925);
FORCEPROP 1 LAST PATH I331
J 0
(-7600 1875);
DISPLAY 0.978723 (-7600 1875);
PAINT WHITE (-7600 1875);
DISPLAY INVISIBLE (-7600 1875);
FORCEPROP 2 LAST SEC 1
J 0
(-7600 1925);
DISPLAY 0.680851 (-7600 1925);
PAINT MONO (-7600 1925);
DISPLAY INVISIBLE (-7600 1925);
FORCEPROP 2 LAST SEC_TYPE 0402
J 0
(-7600 1925);
DISPLAY 1.021277 (-7600 1925);
PAINT ORANGE (-7600 1925);
DISPLAY INVISIBLE (-7600 1925);
FORCEADD P3V3_STBY..1
(-7650 1950);
FORCEPROP 3 LASTPIN (-7650 1900) SIG_NAME P3V3_STBY\g
J 0
(-7640 1910);
DISPLAY 0.659574 (-7640 1910);
PAINT MONO (-7640 1910);
DISPLAY INVISIBLE (-7640 1910);
FORCEPROP 1 LAST VOLTAGE 3.3V
J 0
(-7695 1907);
DISPLAY 0.340426 (-7695 1907);
PAINT SKYBLUE (-7695 1907);
DISPLAY INVISIBLE (-7695 1907);
FORCEPROP 1 LAST PATH I332
J 0
(-7605 1952);
DISPLAY 0.340426 (-7605 1952);
PAINT GREEN (-7605 1952);
DISPLAY INVISIBLE (-7605 1952);
FORCEPROP 2 LAST CDS_LIB mstr_symbols
J 0
(-7650 1950);
PAINT ORANGE (-7650 1950);
DISPLAY INVISIBLE (-7650 1950);
FORCEPROP 1 LAST SIZE 1B
J 0
(-7605 1972);
DISPLAY 0.340426 (-7605 1972);
PAINT GREEN (-7605 1972);
DISPLAY INVISIBLE (-7605 1972);
FORCEPROP 1 LAST BODY_TYPE PLUMBING
J 0
(-7695 1907);
DISPLAY 0.340426 (-7695 1907);
PAINT GREEN (-7695 1907);
DISPLAY INVISIBLE (-7695 1907);
FORCEPROP 1 LAST HDL_POWER P3V3_STBY
J 0
(-7950 1825);
DISPLAY 0.872340 (-7950 1825);
PAINT ORANGE (-7950 1825);
DISPLAY INVISIBLE (-7950 1825);
FORCEADD RES..2
(-7650 1325);
FORCEPROP 1 LASTPIN (-7650 1225) $PN 2
J 0
(-7645 1235);
DISPLAY 0.617021 (-7645 1235);
PAINT ORANGE (-7645 1235);
FORCEPROP 1 LAST PACK_TYPE 0402
J 0
(-7610 1150);
DISPLAY 0.617021 (-7610 1150);
PAINT SKYBLUE (-7610 1150);
FORCEPROP 1 LAST MATERIAL CHIP
J 0
(-7610 1250);
DISPLAY 0.617021 (-7610 1250);
PAINT SKYBLUE (-7610 1250);
FORCEPROP 1 LASTPIN (-7650 1425) $PN 1
J 0
(-7645 1387);
DISPLAY 0.617021 (-7645 1387);
PAINT ORANGE (-7645 1387);
FORCEPROP 1 LAST LOCATION R3P56
J 0
(-7605 1450);
DISPLAY 0.617021 (-7605 1450);
PAINT AQUA (-7605 1450);
FORCEPROP 1 LAST VALUE 1.00K
J 0
(-7605 1400);
DISPLAY 0.617021 (-7605 1400);
PAINT SKYBLUE (-7605 1400);
FORCEPROP 1 LAST TOLERANCE 1%
J 0
(-7605 1350);
DISPLAY 0.617021 (-7605 1350);
PAINT SKYBLUE (-7605 1350);
FORCEPROP 1 LAST WATTAGE 1/16W
J 0
(-7610 1300);
DISPLAY 0.617021 (-7610 1300);
PAINT SKYBLUE (-7610 1300);
FORCEPROP 1 LAST PART_NUMBER G21796-026
J 0
(-7610 1200);
DISPLAY 0.617021 (-7610 1200);
PAINT BLUE (-7610 1200);
FORCEPROP 2 LAST CDS_LIB mstr_discrete
J 0
(-7650 1325);
PAINT ORANGE (-7650 1325);
DISPLAY INVISIBLE (-7650 1325);
FORCEPROP 1 LAST PATH I333
J 0
(-7600 1500);
DISPLAY 0.978723 (-7600 1500);
PAINT WHITE (-7600 1500);
DISPLAY INVISIBLE (-7600 1500);
FORCEPROP 0 LAST ROOM CPU0
J 0
(-7600 1550);
DISPLAY 1.021277 (-7600 1550);
PAINT ORANGE (-7600 1550);
DISPLAY INVISIBLE (-7600 1550);
FORCEPROP 2 LAST SEC 1
J 0
(-7600 1550);
DISPLAY 0.680851 (-7600 1550);
PAINT MONO (-7600 1550);
DISPLAY INVISIBLE (-7600 1550);
FORCEPROP 2 LAST SEC_TYPE 0402
J 0
(-7600 1550);
DISPLAY 1.021277 (-7600 1550);
PAINT ORANGE (-7600 1550);
DISPLAY INVISIBLE (-7600 1550);
FORCEADD GND..1
(-7650 1075);
FORCEPROP 3 LASTPIN (-7650 1125) SIG_NAME GND\g
J 0
(-7640 1135);
DISPLAY 0.659574 (-7640 1135);
PAINT MONO (-7640 1135);
DISPLAY INVISIBLE (-7640 1135);
FORCEPROP 1 LAST VOLTAGE 0.0V
J 0
(-7695 1032);
DISPLAY 0.340426 (-7695 1032);
PAINT SKYBLUE (-7695 1032);
DISPLAY INVISIBLE (-7695 1032);
FORCEPROP 2 LAST CDS_LIB mstr_symbols
J 0
(-7650 1075);
PAINT ORANGE (-7650 1075);
DISPLAY INVISIBLE (-7650 1075);
FORCEPROP 1 LAST SIZE 1B
J 0
(-7575 1025);
DISPLAY 0.872340 (-7575 1025);
PAINT AQUA (-7575 1025);
DISPLAY INVISIBLE (-7575 1025);
FORCEPROP 1 LAST PATH I334
J 0
(-7575 1075);
DISPLAY 0.872340 (-7575 1075);
PAINT AQUA (-7575 1075);
DISPLAY INVISIBLE (-7575 1075);
FORCEPROP 1 LAST BODY_TYPE PLUMBING
J 0
(-7695 1032);
DISPLAY 0.340426 (-7695 1032);
PAINT GREEN (-7695 1032);
DISPLAY INVISIBLE (-7695 1032);
FORCEPROP 1 LAST HDL_POWER GND
J 0
(-7650 1225);
DISPLAY 0.872340 (-7650 1225);
PAINT GREEN (-7650 1225);
DISPLAY INVISIBLE (-7650 1225);
FORCEADD OFFPAGE..2
(-4925 1550);
FORCEPROP 2 LAST $XR0 55 
J 0
(-4736 1550);
DISPLAY 0.638298 (-4736 1550);
PAINT MONO (-4736 1550);
FORCEPROP 2 LAST PATH I335
J 0
(-4750 1625);
DISPLAY 1.021277 (-4750 1625);
PAINT ORANGE (-4750 1625);
DISPLAY INVISIBLE (-4750 1625);
FORCEPROP 2 LAST CDS_LIB mstr_standard
J 0
(-4925 1550);
PAINT ORANGE (-4925 1550);
DISPLAY INVISIBLE (-4925 1550);
FORCEPROP 1 LAST OFFPAGE TRUE
J 0
(-4600 1425);
DISPLAY 0.872340 (-4600 1425);
PAINT GREEN (-4600 1425);
DISPLAY INVISIBLE (-4600 1425);
FORCEPROP 1 LAST COMMENT_BODY TRUE
J 0
(-4970 1455);
DISPLAY 0.872340 (-4970 1455);
PAINT GREEN (-4970 1455);
DISPLAY INVISIBLE (-4970 1455);
FORCEADD RES..2
(-6025 1725);
FORCEPROP 1 LASTPIN (-6025 1625) $PN 2
J 0
(-6020 1635);
DISPLAY 0.617021 (-6020 1635);
PAINT ORANGE (-6020 1635);
FORCEPROP 1 LASTPIN (-6025 1825) $PN 1
J 0
(-6020 1787);
DISPLAY 0.617021 (-6020 1787);
PAINT ORANGE (-6020 1787);
FORCEPROP 1 LAST PACK_TYPE 0402
J 0
(-5985 1550);
DISPLAY 0.617021 (-5985 1550);
PAINT SKYBLUE (-5985 1550);
FORCEPROP 1 LAST VALUE 3.32K
J 0
(-5930 1800);
DISPLAY 0.617021 (-5930 1800);
PAINT SKYBLUE (-5930 1800);
FORCEPROP 1 LAST PART_NUMBER G21796-027
J 0
(-5985 1600);
DISPLAY 0.617021 (-5985 1600);
PAINT BLUE (-5985 1600);
FORCEPROP 1 LAST LOCATION R1C35
J 0
(-5980 1850);
DISPLAY 0.617021 (-5980 1850);
PAINT AQUA (-5980 1850);
FORCEPROP 1 LAST MATERIAL EMPTY
J 0
(-5910 1650);
DISPLAY 0.617021 (-5910 1650);
PAINT RED (-5910 1650);
FORCEPROP 1 LAST WATTAGE 1/16W
J 0
(-5885 1700);
DISPLAY 0.617021 (-5885 1700);
PAINT SKYBLUE (-5885 1700);
FORCEPROP 1 LAST TOLERANCE 1%
J 0
(-5855 1750);
DISPLAY 0.617021 (-5855 1750);
PAINT SKYBLUE (-5855 1750);
FORCEPROP 2 LAST CDS_LIB mstr_discrete
J 0
(-6025 1725);
PAINT ORANGE (-6025 1725);
DISPLAY INVISIBLE (-6025 1725);
FORCEPROP 2 LAST SEC_TYPE 0402
J 0
(-5975 1950);
DISPLAY 1.021277 (-5975 1950);
PAINT ORANGE (-5975 1950);
DISPLAY INVISIBLE (-5975 1950);
FORCEPROP 2 LAST SEC 1
J 0
(-5975 1950);
DISPLAY 0.680851 (-5975 1950);
PAINT MONO (-5975 1950);
DISPLAY INVISIBLE (-5975 1950);
FORCEPROP 1 LAST PATH I336
J 0
(-5975 1900);
DISPLAY 0.978723 (-5975 1900);
PAINT WHITE (-5975 1900);
DISPLAY INVISIBLE (-5975 1900);
FORCEPROP 0 LAST ROOM CPU1
J 0
(-5975 1950);
DISPLAY 1.021277 (-5975 1950);
PAINT ORANGE (-5975 1950);
DISPLAY INVISIBLE (-5975 1950);
FORCEADD RES..2
(-6025 1350);
FORCEPROP 1 LASTPIN (-6025 1250) $PN 2
J 0
(-6020 1260);
DISPLAY 0.617021 (-6020 1260);
PAINT ORANGE (-6020 1260);
FORCEPROP 1 LASTPIN (-6025 1450) $PN 1
J 0
(-6020 1412);
DISPLAY 0.617021 (-6020 1412);
PAINT ORANGE (-6020 1412);
FORCEPROP 1 LAST LOCATION R1C36
J 0
(-5980 1475);
DISPLAY 0.617021 (-5980 1475);
PAINT AQUA (-5980 1475);
FORCEPROP 1 LAST PACK_TYPE 0402
J 0
(-5985 1175);
DISPLAY 0.617021 (-5985 1175);
PAINT SKYBLUE (-5985 1175);
FORCEPROP 1 LAST PART_NUMBER G21796-026
J 0
(-5985 1225);
DISPLAY 0.617021 (-5985 1225);
PAINT BLUE (-5985 1225);
FORCEPROP 1 LAST MATERIAL CHIP
J 0
(-5985 1275);
DISPLAY 0.617021 (-5985 1275);
PAINT SKYBLUE (-5985 1275);
FORCEPROP 1 LAST WATTAGE 1/16W
J 0
(-5985 1325);
DISPLAY 0.617021 (-5985 1325);
PAINT SKYBLUE (-5985 1325);
FORCEPROP 1 LAST VALUE 1.00K
J 0
(-5980 1425);
DISPLAY 0.617021 (-5980 1425);
PAINT SKYBLUE (-5980 1425);
FORCEPROP 1 LAST TOLERANCE 1%
J 0
(-5980 1375);
DISPLAY 0.617021 (-5980 1375);
PAINT SKYBLUE (-5980 1375);
FORCEPROP 2 LAST CDS_LIB mstr_discrete
J 0
(-6025 1350);
PAINT ORANGE (-6025 1350);
DISPLAY INVISIBLE (-6025 1350);
FORCEPROP 1 LAST PATH I337
J 0
(-5975 1525);
DISPLAY 0.978723 (-5975 1525);
PAINT WHITE (-5975 1525);
DISPLAY INVISIBLE (-5975 1525);
FORCEPROP 2 LAST SEC_TYPE 0402
J 0
(-5975 1575);
DISPLAY 1.021277 (-5975 1575);
PAINT ORANGE (-5975 1575);
DISPLAY INVISIBLE (-5975 1575);
FORCEPROP 2 LAST SEC 1
J 0
(-5975 1575);
DISPLAY 0.680851 (-5975 1575);
PAINT MONO (-5975 1575);
DISPLAY INVISIBLE (-5975 1575);
FORCEPROP 0 LAST ROOM CPU1
J 0
(-5975 1575);
DISPLAY 1.021277 (-5975 1575);
PAINT ORANGE (-5975 1575);
DISPLAY INVISIBLE (-5975 1575);
FORCEADD GND..1
(-6025 1100);
FORCEPROP 3 LASTPIN (-6025 1150) SIG_NAME GND\g
J 0
(-6015 1160);
DISPLAY 0.659574 (-6015 1160);
PAINT MONO (-6015 1160);
DISPLAY INVISIBLE (-6015 1160);
FORCEPROP 1 LAST VOLTAGE 0.0V
J 0
(-6070 1057);
DISPLAY 0.340426 (-6070 1057);
PAINT SKYBLUE (-6070 1057);
DISPLAY INVISIBLE (-6070 1057);
FORCEPROP 2 LAST CDS_LIB mstr_symbols
J 0
(-6025 1100);
PAINT ORANGE (-6025 1100);
DISPLAY INVISIBLE (-6025 1100);
FORCEPROP 1 LAST PATH I338
J 0
(-5950 1100);
DISPLAY 0.872340 (-5950 1100);
PAINT AQUA (-5950 1100);
DISPLAY INVISIBLE (-5950 1100);
FORCEPROP 1 LAST SIZE 1B
J 0
(-5950 1050);
DISPLAY 0.872340 (-5950 1050);
PAINT AQUA (-5950 1050);
DISPLAY INVISIBLE (-5950 1050);
FORCEPROP 1 LAST BODY_TYPE PLUMBING
J 0
(-6070 1057);
DISPLAY 0.340426 (-6070 1057);
PAINT GREEN (-6070 1057);
DISPLAY INVISIBLE (-6070 1057);
FORCEPROP 1 LAST HDL_POWER GND
J 0
(-6025 1250);
DISPLAY 0.872340 (-6025 1250);
PAINT GREEN (-6025 1250);
DISPLAY INVISIBLE (-6025 1250);
FORCEADD P3V3_STBY..1
(-6025 1975);
FORCEPROP 3 LASTPIN (-6025 1925) SIG_NAME P3V3_STBY\g
J 0
(-6015 1935);
DISPLAY 0.659574 (-6015 1935);
PAINT MONO (-6015 1935);
DISPLAY INVISIBLE (-6015 1935);
FORCEPROP 2 LAST CDS_LIB mstr_symbols
J 0
(-6025 1975);
PAINT ORANGE (-6025 1975);
DISPLAY INVISIBLE (-6025 1975);
FORCEPROP 1 LAST VOLTAGE 3.3V
J 0
(-6070 1932);
DISPLAY 0.340426 (-6070 1932);
PAINT SKYBLUE (-6070 1932);
DISPLAY INVISIBLE (-6070 1932);
FORCEPROP 1 LAST PATH I339
J 0
(-5980 1977);
DISPLAY 0.340426 (-5980 1977);
PAINT GREEN (-5980 1977);
DISPLAY INVISIBLE (-5980 1977);
FORCEPROP 1 LAST SIZE 1B
J 0
(-5980 1997);
DISPLAY 0.340426 (-5980 1997);
PAINT GREEN (-5980 1997);
DISPLAY INVISIBLE (-5980 1997);
FORCEPROP 1 LAST BODY_TYPE PLUMBING
J 0
(-6070 1932);
DISPLAY 0.340426 (-6070 1932);
PAINT GREEN (-6070 1932);
DISPLAY INVISIBLE (-6070 1932);
FORCEPROP 1 LAST HDL_POWER P3V3_STBY
J 0
(-6325 1850);
DISPLAY 0.872340 (-6325 1850);
PAINT ORANGE (-6325 1850);
DISPLAY INVISIBLE (-6325 1850);
FORCEADD DNS..2
(-2895 1820);
PAINT RED (-2895 1820);
FORCEPROP 2 LAST CDS_LIB mstr_misc
J 0
(-2895 1820);
PAINT ORANGE (-2895 1820);
DISPLAY INVISIBLE (-2895 1820);
FORCEPROP 1 LAST COMMENT_BODY TRUE
R 1
J 0
(-2820 1595);
DISPLAY 0.872340 (-2820 1595);
PAINT GREEN (-2820 1595);
DISPLAY INVISIBLE (-2820 1595);
FORCEADD CAD_NOTE..1
(-925 4600);
FORCEPROP 0 LAST L1 PLACE 0.1UF CAP
J 2
(-700 4475);
DISPLAY 1.021277 (-700 4475);
PAINT ORANGE (-700 4475);
FORCEPROP 0 LAST L2 NEXT TO VCC PIN OF
J 2
(-700 4400);
DISPLAY 1.021277 (-700 4400);
PAINT ORANGE (-700 4400);
FORCEPROP 0 LAST L3 74LVC2G07
J 2
(-700 4325);
DISPLAY 1.021277 (-700 4325);
PAINT ORANGE (-700 4325);
FORCEPROP 2 LAST CDS_LIB mstr_symbols
J 0
(-925 4600);
PAINT ORANGE (-925 4600);
DISPLAY INVISIBLE (-925 4600);
FORCEPROP 1 LAST COMMENT_BODY TRUE
J 0
(-900 4700);
DISPLAY 0.978723 (-900 4700);
PAINT ORANGE (-900 4700);
DISPLAY INVISIBLE (-900 4700);
FORCEADD CAD_NOTE..1
(-900 3700);
FORCEPROP 0 LAST L2 NEXT TO VCC PIN OF
J 2
(-675 3500);
DISPLAY 1.021277 (-675 3500);
PAINT ORANGE (-675 3500);
FORCEPROP 0 LAST L1 PLACE 0.1UF CAP
J 2
(-675 3575);
DISPLAY 1.021277 (-675 3575);
PAINT ORANGE (-675 3575);
FORCEPROP 0 LAST L3 74LVC2G07
J 2
(-675 3425);
DISPLAY 1.021277 (-675 3425);
PAINT ORANGE (-675 3425);
FORCEPROP 2 LAST CDS_LIB mstr_symbols
J 0
(-900 3700);
PAINT ORANGE (-900 3700);
DISPLAY INVISIBLE (-900 3700);
FORCEPROP 1 LAST COMMENT_BODY TRUE
J 0
(-875 3800);
DISPLAY 0.978723 (-875 3800);
PAINT ORANGE (-875 3800);
DISPLAY INVISIBLE (-875 3800);
FORCEADD DNS..2
(-2895 1545);
PAINT RED (-2895 1545);
FORCEPROP 2 LAST CDS_LIB mstr_misc
J 0
(-2895 1545);
PAINT ORANGE (-2895 1545);
DISPLAY INVISIBLE (-2895 1545);
FORCEPROP 1 LAST COMMENT_BODY TRUE
R 1
J 0
(-2820 1320);
DISPLAY 0.872340 (-2820 1320);
PAINT GREEN (-2820 1320);
DISPLAY INVISIBLE (-2820 1320);
FORCEADD DNS..2
(-7645 1695);
PAINT RED (-7645 1695);
FORCEPROP 2 LAST CDS_LIB mstr_misc
J 0
(-7645 1695);
PAINT ORANGE (-7645 1695);
DISPLAY INVISIBLE (-7645 1695);
FORCEPROP 1 LAST COMMENT_BODY TRUE
R 1
J 0
(-7570 1470);
DISPLAY 0.872340 (-7570 1470);
PAINT GREEN (-7570 1470);
DISPLAY INVISIBLE (-7570 1470);
FORCEADD DNS..2
(-6020 1720);
PAINT RED (-6020 1720);
FORCEPROP 2 LAST CDS_LIB mstr_misc
J 0
(-6020 1720);
PAINT ORANGE (-6020 1720);
DISPLAY INVISIBLE (-6020 1720);
FORCEPROP 1 LAST COMMENT_BODY TRUE
R 1
J 0
(-5945 1495);
DISPLAY 0.872340 (-5945 1495);
PAINT GREEN (-5945 1495);
DISPLAY INVISIBLE (-5945 1495);
FORCEADD INTEL_CORP_BPAGE..1
(0 0);
FORCEPROP 1 LAST CDS_CON_LAST_MODIFIED Tue Dec 01 11:52:09 2015
J 0
(-1425 325);
DISPLAY 1.361702 (-1425 325);
PAINT GREEN (-1425 325);
DISPLAY INVISIBLE (-1425 325);
FORCEPROP 1 LAST CUSTOM_TXT_CDS <CURRENT_DESIGN_SHEET> OF <TOTAL_DESIGN_SHEETS>
J 0
(-500 25);
PAINT GREEN (-500 25);
FORCEPROP 1 LAST CUSTOM_TXT_CDS <CON_LAST_MODIFIED>
J 0
(-1925 350);
PAINT GREEN (-1925 350);
FORCEPROP 2 LAST CUSTOM_TXT_CDS <XR_PAGE_TITLE>
J 0
(-7890 5250);
DISPLAY 0.638298 (-7890 5250);
PAINT PINK (-7890 5250);
DISPLAY INVISIBLE (-7890 5250);
FORCEPROP 1 LAST SCH_TITLE BMC MISC (1 OF 2)
J 0
(-7950 50);
DISPLAY 1.212766 (-7950 50);
PAINT ORANGE (-7950 50);
FORCEPROP 1 LAST SCH_ADDRESS1 2200 Mission College Blvd.
J 0
(-3975 125);
DISPLAY 0.617021 (-3975 125);
PAINT GREEN (-3975 125);
FORCEPROP 1 LAST SCH_ADDRESS2 P.O. BOX 58119
J 0
(-3975 75);
DISPLAY 0.617021 (-3975 75);
PAINT GREEN (-3975 75);
FORCEPROP 1 LAST SCH_ADDRESS3 Santa Clara, CA 95052-8119
J 0
(-3975 25);
DISPLAY 0.617021 (-3975 25);
PAINT GREEN (-3975 25);
FORCEPROP 1 LAST SCH_REV 2.420
J 0
(-250 150);
DISPLAY 0.978723 (-250 150);
PAINT YELLOW (-250 150);
FORCEPROP 1 LAST SCH_DEPT BESD
J 1
(-4450 100);
DISPLAY 1.212766 (-4450 100);
PAINT YELLOW (-4450 100);
FORCEPROP 1 LAST SCH_NUMBER H4694802
J 0
(-1300 150);
DISPLAY 1.212766 (-1300 150);
PAINT YELLOW (-1300 150);
FORCEPROP 2 LAST PAGE_BORDER TRUE
J 0
(-7890 5250);
DISPLAY 0.851064 (-7890 5250);
PAINT PINK (-7890 5250);
DISPLAY INVISIBLE (-7890 5250);
FORCEPROP 2 LAST CDS_LIB mstr_symbols
J 0
(0 0);
DISPLAY 1.361702 (0 0);
PAINT ORANGE (0 0);
DISPLAY INVISIBLE (0 0);
FORCEPROP 1 LAST COMMENT_BODY TRUE
J 0
(12 12);
DISPLAY 0.617021 (12 12);
PAINT GREEN (12 12);
DISPLAY INVISIBLE (12 12);
FORCEPROP 2 LAST CDS_XR_PAGE_TITLE CR-156 : @BASEBOARD_FAB2_LIB.BASEBOARD_FAB2(SCH_1):PAGE156
J 0
(-7890 5250);
DISPLAY 0.638298 (-7890 5250);
PAINT PINK (-7890 5250);
DISPLAY INVISIBLE (-7890 5250);
FORCEADD DNS..2
(-6595 2345);
PAINT RED (-6595 2345);
FORCEPROP 2 LAST CDS_LIB mstr_misc
J 0
(-6595 2345);
PAINT ORANGE (-6595 2345);
DISPLAY INVISIBLE (-6595 2345);
FORCEPROP 1 LAST COMMENT_BODY TRUE
R 1
J 0
(-6520 2120);
DISPLAY 0.872340 (-6520 2120);
PAINT GREEN (-6520 2120);
DISPLAY INVISIBLE (-6520 2120);
WIRE 16 -1 (-3825 4550)(-3825 4675);
WIRE 16 -1 (-3825 4675)(-4150 4675);
WIRE 16 -1 (-4150 4800)(-4150 4675);
WIRE 16 -1 (-4150 4675)(-4150 4550);
WIRE 16 -1 (-2275 4525)(-2275 4675);
WIRE 16 -1 (-2275 4675)(-2400 4675);
WIRE 16 -1 (-2550 4675)(-2400 4675);
WIRE 16 -1 (-2400 4800)(-2400 4675);
WIRE 16 -1 (-2550 4675)(-2550 4550);
WIRE 16 -1 (-6825 3225)(-6825 3125);
WIRE 16 -1 (-7275 4275)(-7275 4475);
WIRE 16 -1 (-7275 4475)(-7500 4475);
WIRE 16 -1 (-3750 3650)(-3750 3775);
WIRE 16 -1 (-3750 3775)(-4075 3775);
WIRE 16 -1 (-4075 3900)(-4075 3775);
WIRE 16 -1 (-4075 3775)(-4075 3650);
WIRE 16 -1 (-450 3800)(-450 3650);
WIRE 16 -1 (-450 3300)(-450 3450);
WIRE 16 -1 (-450 4200)(-450 4350);
WIRE 16 -1 (-450 4700)(-450 4550);
WIRE 16 -1 (-7275 3700)(-7475 3700);
WIRE 16 -1 (-7275 3525)(-7275 3700);
WIRE 16 -1 (-4275 975)(-4100 975);
WIRE 16 -1 (-4275 775)(-4275 975);
WIRE 16 -1 (-4275 775)(-4100 775);
WIRE 16 -1 (-4275 575)(-4275 775);
WIRE 16 -1 (-4275 575)(-4100 575);
WIRE 16 -1 (-4275 475)(-4275 575);
WIRE 16 -1 (-2175 775)(-2000 775);
WIRE 16 -1 (-2175 575)(-2175 775);
WIRE 16 -1 (-2175 575)(-2000 575);
WIRE 16 -1 (-2175 475)(-2175 575);
WIRE 16 -1 (-2175 975)(-2000 975);
WIRE 16 -1 (-2175 1050)(-2175 975);
WIRE 16 -1 (-7650 1900)(-7650 1800);
WIRE 16 -1 (-7650 1125)(-7650 1225);
WIRE 16 -1 (-6025 1150)(-6025 1250);
WIRE 16 -1 (-6025 1925)(-6025 1825);
WIRE 16 -1 (-7500 4525)(-6575 4525);
FORCEPROP 2 LAST SIG_NAME SMB_HOST_STBY_LVC3_SDA
J 2
(-6585 4535);
DISPLAY 0.617021 (-6585 4535);
PAINT ORANGE (-6585 4535);
WIRE 16 -1 (-7500 4425)(-6575 4425);
FORCEPROP 2 LAST SIG_NAME SMB_HOST_STBY_LVC3_SCL
J 2
(-6585 4435);
DISPLAY 0.617021 (-6585 4435);
PAINT ORANGE (-6585 4435);
WIRE 16 -1 (-7650 1600)(-7650 1525);
WIRE 16 -1 (-6600 1525)(-7650 1525);
FORCEPROP 2 LAST SIG_NAME FM_CPU0_SM_WP
J 0
(-7210 1535);
DISPLAY 0.617021 (-7210 1535);
PAINT ORANGE (-7210 1535);
WIRE 16 -1 (-7650 1425)(-7650 1525);
WIRE 16 -1 (-7475 3650)(-6550 3650);
FORCEPROP 2 LAST SIG_NAME SMB_SMLINK0_STBY_LVC3_SCL
J 2
(-6560 3660);
DISPLAY 0.617021 (-6560 3660);
PAINT ORANGE (-6560 3660);
WIRE 16 -1 (-7475 3750)(-6550 3750);
FORCEPROP 2 LAST SIG_NAME SMB_SMLINK0_STBY_LVC3_SDA
J 2
(-6560 3760);
DISPLAY 0.617021 (-6560 3760);
PAINT ORANGE (-6560 3760);
WIRE 16 -1 (-6700 2350)(-7400 2350);
FORCEPROP 2 LAST SIG_NAME FM_MEM_THERM_EVENT_LVT3_N
J 0
(-7360 2360);
DISPLAY 0.617021 (-7360 2360);
PAINT ORANGE (-7360 2360);
WIRE 16 -1 (-6825 2925)(-6825 2775);
WIRE 16 -1 (-6825 2775)(-6675 2775);
WIRE 16 -1 (-7400 2775)(-6825 2775);
FORCEPROP 2 LAST SIG_NAME IRQ_BMC_PCH_NMI_STBY_N
J 0
(-7335 2785);
DISPLAY 0.617021 (-7335 2785);
PAINT ORANGE (-7335 2785);
WIRE 16 -1 (-6325 850)(-5400 850);
FORCEPROP 2 LAST SIG_NAME SMB_PIROM_CPU1_SDA
J 2
(-5385 860);
DISPLAY 0.617021 (-5385 860);
PAINT ORANGE (-5385 860);
WIRE 16 -1 (-6500 2350)(-5900 2350);
FORCEPROP 2 LAST SIG_NAME FM_ADR_SMI_GPIO_N
J 0
(-6410 2360);
DISPLAY 0.617021 (-6410 2360);
PAINT ORANGE (-6410 2360);
WIRE 16 -1 (-6475 2775)(-5900 2775);
FORCEPROP 2 LAST SIG_NAME IRQ_BMC_PCH_NMI_STBY_R_N
J 0
(-6435 2785);
DISPLAY 0.617021 (-6435 2785);
PAINT ORANGE (-6435 2785);
WIRE 16 3135 (-7875 3400)(-5025 3400);
WIRE 16 -1 (-6025 1625)(-6025 1550);
WIRE 16 -1 (-4975 1550)(-6025 1550);
FORCEPROP 2 LAST SIG_NAME FM_CPU1_SM_WP
J 0
(-5585 1560);
DISPLAY 0.617021 (-5585 1560);
PAINT ORANGE (-5585 1560);
WIRE 16 -1 (-6025 1450)(-6025 1550);
WIRE 16 3135 (-4975 4050)(-4975 4850);
WIRE 16 3135 (-4975 4050)(-4975 3050);
WIRE 16 3135 (-7875 4050)(-4975 4050);
WIRE 16 -1 (-4150 4350)(-4150 4100);
WIRE 16 -1 (-4150 4100)(-3300 4100);
WIRE 16 -1 (-4575 4100)(-4150 4100);
FORCEPROP 2 LAST SIG_NAME FM_BMC_PWRBTN_OUT_N
J 0
(-4535 4110);
DISPLAY 0.617021 (-4535 4110);
PAINT ORANGE (-4535 4110);
WIRE 16 3135 (-4975 3000)(-75 3000);
WIRE 16 -1 (-3900 575)(-3000 575);
FORCEPROP 2 LAST SIG_NAME PD_PIROM_CPU0_ADDR2
J 0
(-3610 585);
DISPLAY 0.617021 (-3610 585);
PAINT ORANGE (-3610 585);
WIRE 16 -1 (-3900 775)(-3000 775);
FORCEPROP 2 LAST SIG_NAME PD_PIROM_CPU0_ADDR1
J 0
(-3610 785);
DISPLAY 0.617021 (-3610 785);
PAINT ORANGE (-3610 785);
WIRE 16 -1 (-3900 975)(-3000 975);
FORCEPROP 2 LAST SIG_NAME PD_PIROM_CPU0_ADDR0
J 0
(-3610 985);
DISPLAY 0.617021 (-3610 985);
PAINT ORANGE (-3610 985);
WIRE 16 -1 (-3150 1550)(-3000 1550);
WIRE 16 -1 (-3150 1550)(-3150 1825);
WIRE 16 -1 (-4025 1550)(-3150 1550);
FORCEPROP 2 LAST SIG_NAME FM_CPU_BMC_INIT
J 0
(-4010 1560);
DISPLAY 0.617021 (-4010 1560);
PAINT ORANGE (-4010 1560);
WIRE 16 -1 (-3150 1825)(-3000 1825);
WIRE 16 -1 (-4075 3450)(-4075 3200);
WIRE 16 -1 (-4075 3200)(-3225 3200);
WIRE 16 -1 (-4500 3200)(-4075 3200);
FORCEPROP 2 LAST SIG_NAME FM_PCH_PWRBTN_OUT_N
J 0
(-4460 3210);
DISPLAY 0.617021 (-4460 3210);
PAINT ORANGE (-4460 3210);
WIRE 16 -1 (-3225 3250)(-3750 3250);
WIRE 16 -1 (-3750 3450)(-3750 3250);
WIRE 16 -1 (-3750 3250)(-4500 3250);
FORCEPROP 2 LAST SIG_NAME RST_PCH_SYSRST_BTN_OUT_N
J 0
(-4460 3260);
DISPLAY 0.617021 (-4460 3260);
PAINT ORANGE (-4460 3260);
WIRE 16 -1 (-2800 1825)(-1875 1825);
FORCEPROP 2 LAST SIG_NAME H_CPU0_BMCINIT
J 2
(-1875 1835);
DISPLAY 0.617021 (-1875 1835);
PAINT ORANGE (-1875 1835);
WIRE 16 -1 (-2800 1550)(-1875 1550);
FORCEPROP 2 LAST SIG_NAME H_CPU1_BMCINIT
J 2
(-1875 1560);
DISPLAY 0.617021 (-1875 1560);
PAINT ORANGE (-1875 1560);
WIRE 16 -1 (-1800 975)(-900 975);
FORCEPROP 2 LAST SIG_NAME PU_PIROM_CPU1_ADDR0
J 0
(-1510 985);
DISPLAY 0.617021 (-1510 985);
PAINT ORANGE (-1510 985);
WIRE 16 -1 (-1800 775)(-900 775);
FORCEPROP 2 LAST SIG_NAME PD_PIROM_CPU1_ADDR1
J 0
(-1510 785);
DISPLAY 0.617021 (-1510 785);
PAINT ORANGE (-1510 785);
WIRE 16 -1 (-1800 575)(-900 575);
FORCEPROP 2 LAST SIG_NAME PD_PIROM_CPU1_ADDR2
J 0
(-1510 585);
DISPLAY 0.617021 (-1510 585);
PAINT ORANGE (-1510 585);
WIRE 16 -1 (-3300 4150)(-3825 4150);
WIRE 16 -1 (-3825 4350)(-3825 4150);
WIRE 16 -1 (-3825 4150)(-4575 4150);
FORCEPROP 2 LAST SIG_NAME RST_BMC_SYSRST_BTN_OUT_N
J 0
(-4535 4160);
DISPLAY 0.617021 (-4535 4160);
PAINT ORANGE (-4535 4160);
WIRE 16 -1 (-2275 4325)(-2275 4150);
WIRE 16 -1 (-2275 4150)(-1800 4150);
WIRE 16 -1 (-2325 4150)(-2275 4150);
WIRE 16 -1 (-2700 4150)(-2325 4150);
WIRE 16 -1 (-2325 3250)(-2325 4150);
FORCEPROP 2 LAST SIG_NAME RST_BMC_SYSRST_BTN_OUT_B_R_N
R 1
J 0
(-2360 3260);
DISPLAY 0.617021 (-2360 3260);
PAINT ORANGE (-2360 3260);
FORCEPROP 2 LASTPROP $XRERR UNIQUE?
J 0
(-2600 3260);
DISPLAY 0.638298 (-2600 3260);
PAINT MONO (-2600 3260);
DISPLAY INVISIBLE (-2600 3260);
WIRE 16 -1 (-2625 3250)(-2325 3250);
WIRE 16 -1 (-2625 3200)(-2275 3200);
WIRE 16 -1 (-2275 3200)(-2275 4100);
WIRE 16 -1 (-2275 4100)(-1800 4100);
FORCEPROP 2 LAST SIG_NAME FM_PCH_PWRBTN_R_N
J 0
(-2260 4110);
DISPLAY 0.617021 (-2260 4110);
PAINT ORANGE (-2260 4110);
FORCEPROP 2 LASTPROP $XRERR UNIQUE?
J 0
(-2500 4110);
DISPLAY 0.638298 (-2500 4110);
PAINT MONO (-2500 4110);
DISPLAY INVISIBLE (-2500 4110);
WIRE 16 -1 (-2275 4100)(-2550 4100);
WIRE 16 -1 (-2550 4350)(-2550 4100);
WIRE 16 -1 (-2700 4100)(-2550 4100);
WIRE 16 -1 (-1600 4100)(-1000 4100);
WIRE 16 -1 (-1600 4150)(-1000 4150);
WIRE 16 -1 (-6325 700)(-5400 700);
FORCEPROP 2 LAST SIG_NAME SMB_PIROM_CPU0_SDA
J 2
(-5385 710);
DISPLAY 0.617021 (-5385 710);
PAINT ORANGE (-5385 710);
WIRE 16 -1 (-6700 400)(-6525 400);
WIRE 16 -1 (-6700 400)(-6700 550);
WIRE 16 -1 (-7300 400)(-6700 400);
FORCEPROP 2 LAST SIG_NAME SMB_LAN_STBY_LVC3_SCL
J 0
(-7260 410);
DISPLAY 0.617021 (-7260 410);
PAINT ORANGE (-7260 410);
WIRE 16 -1 (-6700 550)(-6525 550);
WIRE 16 -1 (-6325 400)(-5400 400);
FORCEPROP 2 LAST SIG_NAME SMB_PIROM_CPU0_SCL
J 2
(-5385 410);
DISPLAY 0.617021 (-5385 410);
PAINT ORANGE (-5385 410);
WIRE 16 -1 (-6325 550)(-5400 550);
FORCEPROP 2 LAST SIG_NAME SMB_PIROM_CPU1_SCL
J 2
(-5385 560);
DISPLAY 0.617021 (-5385 560);
PAINT ORANGE (-5385 560);
WIRE 16 -1 (-6700 700)(-6525 700);
WIRE 16 -1 (-6700 700)(-6700 850);
WIRE 16 -1 (-7300 700)(-6700 700);
FORCEPROP 2 LAST SIG_NAME SMB_LAN_STBY_LVC3_SDA
J 0
(-7260 710);
DISPLAY 0.617021 (-7260 710);
PAINT ORANGE (-7260 710);
WIRE 16 -1 (-6700 850)(-6525 850);
DOT 1 (-7650 1525);
DOT 1 (-6700 400);
DOT 1 (-6700 700);
DOT 1 (-6825 2775);
DOT 1 (-6025 1550);
DOT 1 (-4275 575);
DOT 1 (-4275 775);
DOT 1 (-4975 4050);
DOT 1 (-4150 4100);
DOT 1 (-4150 4675);
DOT 1 (-3150 1550);
DOT 1 (-2175 575);
DOT 1 (-4075 3200);
DOT 1 (-3750 3250);
DOT 1 (-4075 3775);
DOT 1 (-2275 4100);
DOT 1 (-2550 4100);
DOT 1 (-3825 4150);
DOT 1 (-2325 4150);
DOT 1 (-2275 4150);
DOT 1 (-2400 4675);
FORCENOTE
ROOM=SM_THERM
(-7775 200) 0;
DISPLAY LEFT (-7775 200);
DISPLAY 0.617021 (-7775 200);
PAINT PURPLE (-7775 200);
FORCENOTE
BMC DEBUG HEADER
(-7250 3925) 0;
DISPLAY LEFT (-7250 3925);
DISPLAY 1.021277 (-7250 3925);
PAINT PURPLE (-7250 3925);
FORCENOTE
ME DEBUG HEADER
(-7150 4725) 0;
DISPLAY LEFT (-7150 4725);
DISPLAY 1.021277 (-7150 4725);
PAINT PURPLE (-7150 4725);
QUIT
